G04 ================== begin FILE IDENTIFICATION RECORD ==================*
G04 Layout Name:  DAT6MTH3AD0_t6m_cm_d_brd_103112_274.brd*
G04 Film Name:    smt.art*
G04 File Format:  Gerber RS274X*
G04 File Origin:  Cadence Allegro 16.3-S048*
G04 Origin Date:  Tue Nov 26 10:18:27 2013*
G04 *
G04 Layer:  VIA CLASS/SOLDERMASK_TOP*
G04 Layer:  PIN/SOLDERMASK_TOP*
G04 Layer:  PACKAGE GEOMETRY/SOLDERMASK_TOP*
G04 Layer:  MANUFACTURING/PHOTOPLOT_OUTLINE*
G04 Layer:  DRAWING FORMAT/TITLE_BLOCK*
G04 Layer:  DRAWING FORMAT/TITLE_DATA_SMT*
G04 Layer:  BOARD GEOMETRY/SOLDERMASK_TOP*
G04 *
G04 Offset:    (0.00 0.00)*
G04 Mirror:    No*
G04 Mode:      Positive*
G04 Rotation:  0*
G04 FullContactRelief:  No*
G04 UndefLineWidth:     6.00*
G04 ================== end FILE IDENTIFICATION RECORD ====================*
%FSLAX25Y25*MOIN*%
%IR0*IPPOS*OFA0.00000B0.00000*MIA0B0*SFA1.00000B1.00000*%
%AMMACRO112*
4,1,28,-.04688,.05023,
-.03054,.05023,
-.03054,.06519,
-.00962,.06519,
-.00962,.05023,
.03507,.05023,
.03507,.04826,
.04688,.04826,
.04688,.02851,
.03507,.02851,
.03507,.02267,
.04688,.02267,
.04688,.00292,
.03507,.00292,
.03507,-.00292,
.04688,-.00292,
.04688,-.02267,
.03507,-.02267,
.03507,-.02851,
.04688,-.02851,
.04688,-.04826,
.03507,-.04826,
.03507,-.05023,
-.00962,-.05023,
-.00962,-.06519,
-.03054,-.06519,
-.03054,-.05023,
-.04688,-.05023,
-.04688,.05023,
0.0*
%
%ADD112MACRO112*%
%AMMACRO111*
4,1,28,.05023,.04688,
.05023,.03054,
.06519,.03054,
.06519,.00962,
.05023,.00962,
.05023,-.03507,
.04826,-.03507,
.04826,-.04688,
.02851,-.04688,
.02851,-.03507,
.02267,-.03507,
.02267,-.04688,
.00292,-.04688,
.00292,-.03507,
-.00292,-.03507,
-.00292,-.04688,
-.02267,-.04688,
-.02267,-.03507,
-.02851,-.03507,
-.02851,-.04688,
-.04826,-.04688,
-.04826,-.03507,
-.05023,-.03507,
-.05023,.00962,
-.06519,.00962,
-.06519,.03054,
-.05023,.03054,
-.05023,.04688,
.05023,.04688,
0.0*
%
%ADD111MACRO111*%
%ADD167R,.13X.044*%
%ADD36R,.034X.13*%
%ADD122R,.044X.113*%
%ADD86R,.103X.037*%
%ADD11R,.006X.012*%
%ADD42R,.037X.103*%
%ADD178O,.123X.067*%
%ADD144R,.132X.073*%
%ADD105R,.02X.008*%
%ADD85R,.103X.084*%
%ADD39R,.052X.134*%
%ADD35R,.034X.17*%
%ADD187O,.067X.123*%
%ADD89C,.012*%
%ADD55R,.084X.103*%
%ADD143R,.036X.17*%
%ADD26O,.044X.139*%
%ADD103C,.015*%
%ADD62R,.109X.073*%
%AMMACRO185*
21,1,.016,.0081,0.0,0.0,45.*%
%ADD185MACRO185*%
%ADD154C,.07*%
%ADD115R,.009X.016*%
%ADD101C,.034*%
%ADD87C,.016*%
%ADD65R,.073X.109*%
%ADD61R,.154X.083*%
%ADD49R,.0081X.016*%
%ADD190R,.083X.154*%
%ADD182C,.0233*%
%ADD168C,.08*%
%ADD166R,.0082X.016*%
%ADD123C,.062*%
%ADD114R,.016X.009*%
%ADD63R,.016X.0081*%
%ADD106R,.016X.0082*%
%ADD51C,.072*%
%ADD17C,.081*%
%ADD170C,.046*%
%ADD15C,.064*%
%ADD164C,.056*%
%ADD107R,.115X.099*%
%ADD10C,.065*%
%ADD136R,.139X.076*%
%ADD129C,.066*%
%ADD31R,.099X.115*%
%ADD135C,.067*%
%ADD73C,.085*%
%ADD24C,.049*%
%ADD158R,.07X.07*%
%AMMACRO84*
4,1,12,-.03645,-.01332,
-.03645,.01332,
-.01473,.01332,
-.01473,.00623,
-.01086,.00623,
-.01086,.01332,
.01086,.01332,
.01086,.00623,
.01473,.00623,
.01473,.01332,
.03645,.01332,
.03645,-.01332,
-.03645,-.01332,
0.0*
%
%ADD84MACRO84*%
%ADD78C,.0185*%
%ADD188R,.062X.062*%
%ADD91R,.071X.071*%
%ADD113R,.036X.036*%
%ADD50R,.072X.072*%
%ADD29R,.081X.081*%
%ADD27C,.079*%
%ADD169R,.046X.046*%
%ADD132R,.028X.028*%
%ADD81R,.091X.091*%
%ADD14R,.064X.064*%
%ADD165R,.056X.056*%
%ADD159R,.065X.065*%
%ADD53R,.134X.0888*%
%ADD96R,.0888X.134*%
%ADD72R,.075X.075*%
%ADD28R,.049X.049*%
%ADD151R,.068X.068*%
%ADD98R,.087X.087*%
%ADD44R,.069X.069*%
%ADD70R,.04X.011*%
%ADD77O,.0135X.01*%
%ADD71R,.011X.04*%
%ADD175R,.051X.011*%
%ADD134R,.042X.011*%
%ADD128R,.024X.02*%
%ADD97O,.01X.0135*%
%ADD172R,.011X.051*%
%ADD139R,.011X.042*%
%ADD90O,.0135X.011*%
%ADD88O,.011X.0135*%
%ADD79R,.04X.014*%
%ADD174R,.044X.011*%
%ADD82R,.05X.032*%
%ADD80R,.014X.04*%
%ADD68R,.022X.024*%
%AMMACRO66*
4,1,28,.04688,-.05023,
.03054,-.05023,
.03054,-.06519,
.00962,-.06519,
.00962,-.05023,
-.03507,-.05023,
-.03507,-.04826,
-.04688,-.04826,
-.04688,-.02851,
-.03507,-.02851,
-.03507,-.02267,
-.04688,-.02267,
-.04688,-.00292,
-.03507,-.00292,
-.03507,.00292,
-.04688,.00292,
-.04688,.02267,
-.03507,.02267,
-.03507,.02851,
-.04688,.02851,
-.04688,.04826,
-.03507,.04826,
-.03507,.05023,
.00962,.05023,
.00962,.06519,
.03054,.06519,
.03054,.05023,
.04688,.05023,
.04688,-.05023,
0.0*
%
%ADD66MACRO66*%
%ADD45R,.04X.015*%
%ADD22R,.024X.022*%
%ADD173R,.011X.044*%
%ADD137R,.024X.014*%
%AMMACRO109*
4,1,28,-.05023,-.04688,
-.05023,-.03054,
-.06519,-.03054,
-.06519,-.00962,
-.05023,-.00962,
-.05023,.03507,
-.04826,.03507,
-.04826,.04688,
-.02851,.04688,
-.02851,.03507,
-.02267,.03507,
-.02267,.04688,
-.00292,.04688,
-.00292,.03507,
.00292,.03507,
.00292,.04688,
.02267,.04688,
.02267,.03507,
.02851,.03507,
.02851,.04688,
.04826,.04688,
.04826,.03507,
.05023,.03507,
.05023,-.00962,
.06519,-.00962,
.06519,-.03054,
.05023,-.03054,
.05023,-.04688,
-.05023,-.04688,
0.0*
%
%ADD109MACRO109*%
%ADD56R,.024X.022*%
%ADD46R,.015X.04*%
%ADD43R,.026X.021*%
%ADD21R,.022X.024*%
%ADD150R,.064X.011*%
%ADD124R,.03X.08*%
%ADD100O,.032X.019*%
%ADD83R,.021X.026*%
%ADD162R,.052X.042*%
%ADD153R,.011X.064*%
%ADD146C,.31*%
%ADD110R,.04X.036*%
%ADD104R,.06X.052*%
%ADD99O,.019X.032*%
%ADD94R,.05X.017*%
%ADD181R,.02X.056*%
%ADD177R,.04X.028*%
%ADD161R,.048X.011*%
%ADD152R,.039X.011*%
%ADD117R,.042X.052*%
%AMMACRO75*
4,1,8,.09255,-.08468,
-.0295,-.08468,
-.0295,-.09452,
-.09255,-.09452,
-.09255,.09452,
-.0295,.09452,
-.0295,.08468,
.09255,.08468,
.09255,-.08468,
0.0*
%
%ADD75MACRO75*%
%ADD69R,.015X.061*%
%ADD40R,.036X.04*%
%ADD33R,.036X.032*%
%ADD16C,.14*%
%ADD171R,.056X.022*%
%ADD160R,.011X.048*%
%ADD155R,.011X.039*%
%ADD138R,.119X.17*%
%ADD127R,.032X.028*%
%ADD116R,.063X.015*%
%ADD93R,.037X.014*%
%ADD74R,.024X.018*%
%ADD59R,.021X.056*%
%ADD37R,.032X.036*%
%AMMACRO157*
21,1,.016,.009,0.0,0.0,135.*%
%ADD157MACRO157*%
%ADD141R,.028X.032*%
%ADD133R,.045X.034*%
%ADD118R,.015X.063*%
%ADD108R,.018X.024*%
%ADD102R,.022X.056*%
%ADD92R,.014X.037*%
%ADD180C,.17*%
%ADD126R,.072X.026*%
%ADD38R,.054X.044*%
%ADD34R,.066X.05*%
%ADD186C,.144*%
%ADD148R,.075X.015*%
%ADD145R,.063X.018*%
%ADD121R,.059X.013*%
%ADD58C,.162*%
%ADD52R,.026X.072*%
%ADD32R,.05X.066*%
%ADD20R,.044X.054*%
%ADD184R,.026X.028*%
%ADD149R,.015X.075*%
%ADD142R,.048X.06*%
%ADD120R,.013X.059*%
%ADD41C,.118*%
%ADD19R,.018X.063*%
%ADD189R,.083X.063*%
%ADD147R,.038X.036*%
%ADD130R,.094X.015*%
%ADD125R,.065X.018*%
%ADD119R,.075X.044*%
%ADD48R,.065X.036*%
%ADD183R,.036X.065*%
%ADD60C,.138*%
%ADD57R,.063X.083*%
%ADD25R,.026X.057*%
%AMMACRO54*
4,1,12,-.01332,.03645,
.01332,.03645,
.01332,.01473,
.00623,.01473,
.00623,.01086,
.01332,.01086,
.01332,-.01086,
.00623,-.01086,
.00623,-.01473,
.01332,-.01473,
.01332,-.03645,
-.01332,-.03645,
-.01332,.03645,
0.0*
%
%ADD54MACRO54*%
%ADD23R,.018X.048*%
%ADD18R,.084X.064*%
%ADD163R,.16X.16*%
%ADD156R,.232X.232*%
%ADD76R,.019X.085*%
%ADD30R,.099X.06*%
%ADD131C,.178*%
%ADD67R,.058X.048*%
%ADD95R,.217X.217*%
%ADD47R,.048X.058*%
%ADD140R,.138X.138*%
%ADD64R,.186X.189*%
%ADD176R,.248X.248*%
%ADD179R,.075X.099*%
%ADD191C,.02*%
%ADD192C,.006*%
%ADD193C,.194*%
G75*
%LPD*%
G75*
G36*
G01X-44872Y130213D02*
G03I0J-5000D01*
G37*
G36*
G01Y146213D02*
G03I0J-5000D01*
G37*
G36*
G01Y237533D02*
G03I0J-5000D01*
G37*
G36*
G01Y253533D02*
G03I0J-5000D01*
G37*
G36*
G01Y733493D02*
G03I0J5000D01*
G37*
G36*
G01Y749493D02*
G03I0J5000D01*
G37*
G36*
G01X-26872Y130213D02*
G03I0J-5000D01*
G37*
G36*
G01X-38072Y132113D02*
X-31972D01*
Y133813D01*
X-38072D01*
X-39672D01*
X-39772D01*
Y132113D01*
X-39672D01*
X-38072D01*
G37*
G36*
G01X-26872Y146213D02*
G03I0J-5000D01*
G37*
G36*
G01Y237533D02*
G03I0J-5000D01*
G37*
G36*
G01X-38072Y239433D02*
X-31972D01*
Y241133D01*
X-38072D01*
X-39672D01*
X-39772D01*
Y239433D01*
X-39672D01*
X-38072D01*
G37*
G36*
G01X-26872Y253533D02*
G03I0J-5000D01*
G37*
G36*
G01X-38872Y238833D02*
G02I0J-800D01*
G37*
G36*
G01X-32872D02*
G02I0J-800D01*
G37*
G36*
G01X-35872D02*
G02I0J-800D01*
G37*
G36*
G01X-26872Y733493D02*
G03I0J5000D01*
G37*
G36*
G01X-33672Y747593D02*
X-39772D01*
Y745893D01*
X-33672D01*
X-32072D01*
X-31972D01*
Y747593D01*
X-32072D01*
X-33672D01*
G37*
G36*
G01X-26872Y749493D02*
G03I0J5000D01*
G37*
G36*
G01X328526Y799372D02*
X49526D01*
Y821672D01*
X328526D01*
Y799372D01*
G37*
G36*
G01X77870Y357848D02*
G03I-5900J0D01*
G37*
G36*
G01X74604Y105511D02*
G02X122248I23822J1D01*
G01X122247Y85629D01*
G02X74605I-23821J198D01*
G01X74604Y105511D01*
G37*
G36*
G01Y719684D02*
G02X122248I23822J1D01*
G01X122247Y699802D01*
G02X74605I-23821J198D01*
G01X74604Y719684D01*
G37*
G36*
G01X111513Y147532D02*
G03I-5900J0D01*
G37*
G36*
G01X153490Y647878D02*
G03I-5900J0D01*
G37*
G36*
G01X379726Y799372D02*
X336926D01*
Y821672D01*
X379726D01*
Y799372D01*
G37*
G36*
G01X413386Y357265D02*
G02I0J19900D01*
G37*
G36*
G01X686796Y799372D02*
X407796D01*
Y821672D01*
X686796D01*
Y799372D01*
G37*
G36*
G01X493670Y513674D02*
G03I-5900J0D01*
G37*
G36*
G01X583780Y395242D02*
G03I-5900J0D01*
G37*
G36*
G01X665155Y105315D02*
G02X712799I23822J0D01*
G01Y85630D01*
G02X665155I-23822J0D01*
G01Y105315D01*
G37*
G36*
G01Y719488D02*
G02X712799I23822J0D01*
G01Y699803D01*
G02X665155I-23822J0D01*
G01Y719488D01*
G37*
G36*
G01X699300Y758198D02*
G03I-5900J0D01*
G37*
G36*
G01X737996Y799372D02*
X695196D01*
Y821672D01*
X737996D01*
Y799372D01*
G37*
G36*
G01X751480Y62870D02*
G03I-5900J0D01*
G37*
%LPC*%
G75*
G36*
G01X108126Y98031D02*
G02X88726I-9700J-12204D01*
G03X89529Y99696I-1324J1665D01*
G01Y105512D01*
G02X107323I8897J0D01*
G01Y99696D01*
G03X108126Y98031I2127J0D01*
G37*
G36*
G01Y712204D02*
G02X88726I-9700J-12204D01*
G03X89529Y713869I-1324J1665D01*
G01Y719685D01*
G02X107323I8897J0D01*
G01Y713869D01*
G03X108126Y712204I2127J0D01*
G37*
G36*
G01X699023Y97551D02*
G02X678930I-10046J-11921D01*
G03X679687Y99177I-1370J1627D01*
G01Y105315D01*
G02X698267I9290J0D01*
G01Y99177D01*
G03X699023Y97551I2127J0D01*
G37*
G36*
G01Y711724D02*
G02X678930I-10046J-11921D01*
G03X679687Y713350I-1370J1627D01*
G01Y719488D01*
G02X698267I9290J0D01*
G01Y713350D01*
G03X699023Y711724I2127J0D01*
G37*
G54D193*
X413386Y377165D03*
%LPD*%
G75*
G54D100*
X190500Y389487D03*
Y392046D03*
Y394605D03*
Y397164D03*
X204358Y392046D03*
Y389487D03*
Y397164D03*
Y394605D03*
G54D110*
X260887Y399450D03*
X268761Y403190D03*
Y395710D03*
X634852Y474939D03*
X634787Y501470D03*
X634887Y488270D03*
X642726Y471199D03*
X642761Y484530D03*
X642726Y478679D03*
X642661Y497730D03*
X642761Y492010D03*
X642661Y505210D03*
X680949Y524536D03*
Y532016D03*
X688823Y528276D03*
G54D101*
X196909Y515342D03*
X208209Y504075D03*
X199565Y506454D03*
X205294Y514368D03*
X205247Y508713D03*
X205195Y522335D03*
X221770Y373780D03*
X217818Y368665D03*
X241215Y374601D03*
X237076Y364113D03*
X239309Y482753D03*
X253960Y135933D03*
X247183Y163107D03*
X253083Y182257D03*
X255643Y192767D03*
X256248Y364633D03*
X257226Y374363D03*
X251856Y373544D03*
X249722Y483208D03*
X244390Y483760D03*
X255055Y483635D03*
X267073Y145007D03*
X263575Y364050D03*
X272031Y374583D03*
X263324Y483388D03*
X283593Y144477D03*
X287993Y364451D03*
X295383Y140527D03*
X293053Y154997D03*
X306782Y292461D03*
X293606Y364305D03*
X314893Y140897D03*
X307574Y149601D03*
X315600Y189807D03*
X307420Y354376D03*
X324393Y146984D03*
X328973Y142937D03*
X335295Y717169D03*
X356515Y683743D03*
X378092Y683915D03*
X399606Y377165D03*
X413386Y363385D03*
X403543Y367322D03*
Y387008D03*
X413386Y390945D03*
X427166Y377165D03*
X423229Y367322D03*
Y387008D03*
X447440Y696900D03*
X461244Y696882D03*
X453940Y697445D03*
X477209Y696918D03*
X466683Y697054D03*
X471768Y696891D03*
X643610Y724087D03*
X643000Y734200D03*
X658050Y672117D03*
X658369Y677774D03*
X659029Y710048D03*
X746000Y475000D03*
G54D120*
X336088Y459022D03*
Y492880D03*
X351836Y459022D03*
X349868D03*
X347899D03*
X345931D03*
X343962D03*
X341994D03*
X340025D03*
X338057D03*
Y492880D03*
X340025D03*
X341994D03*
X343962D03*
X345931D03*
X347899D03*
X349868D03*
X351836D03*
X357742Y459022D03*
X355773D03*
X353805D03*
Y492880D03*
X355773D03*
X357742D03*
G54D102*
X193473Y688002D03*
X189733D03*
X185993D03*
Y678356D03*
X193473D03*
X207473Y688002D03*
X203733D03*
X199993D03*
Y678356D03*
X207473D03*
X226993Y688002D03*
Y678356D03*
X220845Y688002D03*
X217105D03*
X213365D03*
Y678356D03*
X220845D03*
X234473Y688002D03*
X230733D03*
X234473Y678356D03*
X240493Y688002D03*
Y678356D03*
X247973Y688002D03*
X244233D03*
X247973Y678356D03*
X257733Y688002D03*
X253993D03*
Y678356D03*
X261473Y688002D03*
Y678356D03*
G54D111*
X271890Y432642D03*
G54D130*
X412330Y243725D03*
Y245694D03*
Y247662D03*
Y249631D03*
Y251599D03*
Y253569D03*
Y255537D03*
Y257505D03*
Y259473D03*
Y261442D03*
Y263410D03*
Y265379D03*
Y267347D03*
Y269316D03*
Y271284D03*
Y273253D03*
Y275222D03*
Y277190D03*
Y279158D03*
Y281127D03*
Y283095D03*
Y285064D03*
Y287032D03*
Y289001D03*
Y290969D03*
Y292938D03*
Y294906D03*
Y296875D03*
Y298843D03*
Y300812D03*
X434882Y243725D03*
Y245694D03*
Y247662D03*
Y249631D03*
Y251599D03*
Y253569D03*
Y255537D03*
Y257505D03*
Y259473D03*
Y261442D03*
Y263410D03*
Y265379D03*
Y267347D03*
Y269316D03*
Y271284D03*
Y273253D03*
Y275222D03*
Y277190D03*
Y279158D03*
Y281127D03*
Y283095D03*
Y285064D03*
Y287032D03*
Y289001D03*
Y290969D03*
Y292938D03*
Y294906D03*
Y296875D03*
Y298843D03*
Y300812D03*
G54D121*
X329986Y465124D03*
Y467093D03*
Y469061D03*
Y471030D03*
Y472998D03*
Y474967D03*
Y476935D03*
Y478904D03*
Y480872D03*
Y482841D03*
Y484809D03*
Y486778D03*
X363844Y471030D03*
Y469061D03*
Y467093D03*
Y465124D03*
Y486778D03*
Y484809D03*
Y482841D03*
Y480872D03*
Y478904D03*
Y476935D03*
Y474967D03*
Y472998D03*
G54D10*
X-44872Y125213D03*
Y141213D03*
Y232533D03*
D03*
Y248533D03*
D03*
Y738493D03*
Y754493D03*
X-26872Y125213D03*
Y141213D03*
Y232533D03*
D03*
Y248533D03*
D03*
Y738493D03*
Y754493D03*
X556181Y81889D03*
G54D103*
X204724Y279523D03*
X207874D03*
X211024D03*
X204724Y282673D03*
Y285823D03*
Y288973D03*
Y292123D03*
Y295273D03*
X207874Y282673D03*
Y285823D03*
Y288973D03*
Y292123D03*
Y295273D03*
X211024Y282673D03*
Y285823D03*
Y288973D03*
Y292123D03*
Y295273D03*
X204724Y301573D03*
Y298423D03*
Y311023D03*
Y307873D03*
Y304723D03*
X207874Y301573D03*
Y298423D03*
Y311023D03*
Y307873D03*
Y304723D03*
X211024Y301573D03*
Y298423D03*
Y311023D03*
Y307873D03*
Y304723D03*
X204724Y314173D03*
X207874Y317323D03*
Y314173D03*
X211024Y317323D03*
Y314173D03*
X204724Y317323D03*
X223624Y279523D03*
X220474D03*
X214174D03*
X217324D03*
X226774D03*
X223624Y282673D03*
X220474D03*
X217324D03*
X214174D03*
X223624Y285823D03*
Y288973D03*
Y292123D03*
Y295273D03*
X220474Y285823D03*
Y288973D03*
Y292123D03*
Y295273D03*
X217324Y285823D03*
Y288973D03*
Y292123D03*
Y295273D03*
X214174Y285823D03*
Y288973D03*
Y292123D03*
Y295273D03*
X226774Y282673D03*
Y295273D03*
Y292123D03*
Y288973D03*
Y285823D03*
X223624Y301573D03*
Y298423D03*
X220474Y301573D03*
Y298423D03*
X217324Y301573D03*
Y298423D03*
X214174Y301573D03*
Y298423D03*
X223624Y311023D03*
Y307873D03*
Y304723D03*
X220474Y311023D03*
Y307873D03*
Y304723D03*
X217324Y311023D03*
Y307873D03*
Y304723D03*
X214174Y311023D03*
Y307873D03*
Y304723D03*
X226774Y298423D03*
Y301573D03*
Y304723D03*
Y307873D03*
Y311023D03*
X223624Y317323D03*
Y314173D03*
X220474Y317323D03*
Y314173D03*
X217324Y317323D03*
Y314173D03*
X214174Y317323D03*
Y314173D03*
X226774D03*
Y317323D03*
X229924Y279523D03*
X236224D03*
X233074D03*
X242524D03*
X239374D03*
X229924Y282673D03*
X236224D03*
X233074D03*
X242524D03*
X239374D03*
X229924Y295273D03*
Y292123D03*
Y288973D03*
Y285823D03*
X236224D03*
Y288973D03*
Y292123D03*
Y295273D03*
X233074Y285823D03*
Y288973D03*
Y292123D03*
Y295273D03*
X242524Y285823D03*
Y288973D03*
Y292123D03*
Y295273D03*
X239374Y285823D03*
Y288973D03*
Y292123D03*
Y295273D03*
X229924Y298423D03*
Y301573D03*
X236224D03*
Y298423D03*
X233074Y301573D03*
Y298423D03*
X242524Y301573D03*
Y298423D03*
X239374Y301573D03*
Y298423D03*
X229924Y304723D03*
Y307873D03*
Y311023D03*
X236224D03*
Y307873D03*
Y304723D03*
X233074Y311023D03*
Y307873D03*
Y304723D03*
X242524Y311023D03*
Y307873D03*
Y304723D03*
X239374Y311023D03*
Y307873D03*
Y304723D03*
X229924Y314173D03*
Y317323D03*
X236224D03*
Y314173D03*
X233074Y317323D03*
Y314173D03*
X242524Y317323D03*
Y314173D03*
X239374Y317323D03*
Y314173D03*
X245674Y279523D03*
X248824D03*
X251974D03*
X245674Y282673D03*
Y285823D03*
Y288973D03*
Y292123D03*
Y295273D03*
X248824Y282673D03*
X251974D03*
X248824Y285823D03*
Y288973D03*
Y292123D03*
Y295273D03*
X251974D03*
Y292123D03*
Y288973D03*
Y285823D03*
X245674Y301573D03*
Y298423D03*
Y311023D03*
Y307873D03*
Y304723D03*
X248824Y301573D03*
Y298423D03*
X251974D03*
Y301573D03*
X248824Y311023D03*
Y307873D03*
Y304723D03*
X251974D03*
Y307873D03*
Y311023D03*
X245674Y317323D03*
Y314173D03*
X248824Y317323D03*
Y314173D03*
X251974D03*
Y317323D03*
G54D112*
X266383Y636830D03*
G54D140*
X423116Y531094D03*
G54D131*
X413386Y377165D03*
G54D20*
X13820Y597179D03*
X9820Y605979D03*
X17820D03*
X70796Y258779D03*
X66796Y267579D03*
X74796D03*
X97449Y181016D03*
X93449Y189816D03*
X101449D03*
X175180Y688329D03*
X179180Y679529D03*
X171180D03*
X175689Y715673D03*
X171689Y724473D03*
X179689D03*
X187440Y699556D03*
X183440Y708356D03*
X191440D03*
X197440D03*
X201440Y699556D03*
X205440Y708356D03*
X211440D03*
X215440Y699556D03*
X219440Y708356D03*
X225940D03*
X229940Y699556D03*
X233940Y708356D03*
X244440Y699556D03*
X240440Y708356D03*
X248440D03*
X258940Y699556D03*
X254940Y708356D03*
X262940D03*
X353298Y638032D03*
X357298Y629232D03*
X361298Y638032D03*
X381218Y629998D03*
X373218D03*
X377218Y638798D03*
X430315Y611073D03*
X426315Y619873D03*
X444135Y611073D03*
X440135Y619873D03*
X448135D03*
X434315D03*
X465165Y595260D03*
X457935Y611073D03*
X461165Y604060D03*
X453935Y619873D03*
X461935D03*
X475795Y281667D03*
X479795Y272867D03*
X471795D03*
X479648Y612832D03*
X469165Y604060D03*
X479832Y628841D03*
X483648Y604032D03*
X487648Y612832D03*
X494282Y628836D03*
X483832Y620041D03*
X487832Y628841D03*
X498282Y620036D03*
X502282Y628836D03*
X512238Y620174D03*
X508238Y628974D03*
X526278Y629595D03*
X522278Y620795D03*
X516238Y628974D03*
X530278Y620795D03*
G54D104*
X209378Y469399D03*
Y462707D03*
X218040Y469399D03*
Y462707D03*
X513167Y422944D03*
X504505D03*
Y429636D03*
X513167D03*
G54D113*
X270135Y702797D03*
Y696891D03*
X318288Y521500D03*
Y527406D03*
X324182Y521508D03*
Y527414D03*
X330182Y521508D03*
Y527414D03*
X336182Y521508D03*
Y527414D03*
X342182Y521508D03*
Y527414D03*
X354182Y521508D03*
Y527414D03*
X348182Y521508D03*
Y527414D03*
X360182Y521508D03*
Y527414D03*
X447440Y703203D03*
Y709109D03*
X453940Y703203D03*
X460940D03*
X453940Y709109D03*
X460940D03*
X467440Y703203D03*
X473940D03*
X480440D03*
X467440Y709109D03*
X473940D03*
X480440D03*
X551129Y280528D03*
X545223D03*
X635408Y511230D03*
X641314D03*
G54D11*
X-34986Y133213D03*
X-36758D03*
X-34986Y240533D03*
X-36758D03*
Y746493D03*
X-34986D03*
G54D122*
X350411Y30188D03*
Y46920D03*
X358285Y30188D03*
X366159D03*
X358285Y46920D03*
X366159D03*
X374033Y30188D03*
X381907D03*
X374033Y46920D03*
X381907D03*
X389781Y30188D03*
X397655D03*
X389781Y46920D03*
X397655D03*
G54D30*
X44279Y374032D03*
Y392536D03*
X162364Y720437D03*
Y738941D03*
G54D141*
X431340Y599929D03*
X435080Y592055D03*
X438820Y599929D03*
X474860Y581398D03*
X471120Y589272D03*
X478600D03*
G54D150*
X495228Y540849D03*
Y542423D03*
Y543998D03*
Y545573D03*
Y547148D03*
Y548723D03*
Y550297D03*
Y551872D03*
Y553447D03*
Y555022D03*
Y556597D03*
Y558171D03*
Y559746D03*
Y561321D03*
Y562896D03*
Y564471D03*
Y566045D03*
Y567620D03*
Y569195D03*
Y570770D03*
Y572345D03*
Y573919D03*
Y575494D03*
Y577069D03*
Y578644D03*
Y580219D03*
Y581793D03*
Y583368D03*
Y584943D03*
Y586518D03*
Y588093D03*
Y589667D03*
X556252Y548723D03*
Y547148D03*
Y545573D03*
Y543998D03*
Y542423D03*
Y540849D03*
Y564471D03*
Y562896D03*
Y561321D03*
Y559746D03*
Y558171D03*
Y556597D03*
Y555022D03*
Y553447D03*
Y551872D03*
Y550297D03*
Y580219D03*
Y578644D03*
Y577069D03*
Y575494D03*
Y573919D03*
Y572345D03*
Y570770D03*
Y569195D03*
Y567620D03*
Y566045D03*
Y589667D03*
Y588093D03*
Y586518D03*
Y584943D03*
Y583368D03*
Y581793D03*
G54D21*
X12178Y612129D03*
X9028D03*
X20020Y658951D03*
X31260Y30414D03*
X34410D03*
Y26414D03*
X31260D03*
X38807Y547034D03*
X37197Y597285D03*
X28105Y595792D03*
X24955D03*
X36937Y608125D03*
X35960Y658951D03*
X32810D03*
X23170D03*
X45355Y14588D03*
X42205D03*
X45355Y18588D03*
X42205D03*
X49817Y494570D03*
X52967D03*
X51325Y518072D03*
X48175D03*
X41957Y547034D03*
X44507Y597285D03*
X47657D03*
X40347D03*
X40087Y608125D03*
X53751Y643928D03*
X40317Y658951D03*
X43467D03*
X53751Y648428D03*
X58654Y115158D03*
X61804D03*
X69485Y188946D03*
X60663Y189182D03*
X63813D03*
X57029Y257049D03*
X60179D03*
X66533Y526417D03*
X63383D03*
Y530417D03*
X66533D03*
X58108Y619407D03*
X54958D03*
X58108Y614907D03*
X54958D03*
X56901Y643928D03*
Y648428D03*
X77895Y172605D03*
X74745D03*
X72635Y188946D03*
X85460Y232861D03*
X82310D03*
X80074Y389621D03*
X76924D03*
X80074Y385722D03*
X76924D03*
X80094Y393857D03*
X76944D03*
X80094Y397913D03*
X76944D03*
X79235Y513104D03*
X76085D03*
X79235Y517104D03*
X76085D03*
Y521104D03*
X79235D03*
X99318Y225836D03*
X96168D03*
X95807Y420074D03*
X92657D03*
X110624Y392023D03*
X113774D03*
X110624Y387978D03*
X113774D03*
X109393Y406383D03*
X106243D03*
X132164Y418152D03*
X129014D03*
X132178Y422320D03*
X129028D03*
X129701Y462738D03*
X132851D03*
X129701Y470738D03*
X132851D03*
X129701Y466738D03*
X132851D03*
Y458733D03*
X129701D03*
X118830Y513831D03*
X121980D03*
X121847Y523033D03*
X118697D03*
X121880Y519031D03*
X118730D03*
X130549Y522895D03*
X124467Y675871D03*
X127617D03*
Y670879D03*
X124467D03*
X120953Y665638D03*
X124103D03*
X129184Y729750D03*
X132334D03*
X129184Y725250D03*
X132334D03*
X137232Y43439D03*
X134082D03*
X134086Y39191D03*
X137236D03*
X134151Y47370D03*
X137301D03*
X143677Y76588D03*
X140527D03*
X133539D03*
X136689D03*
X144701Y296735D03*
X141551D03*
X142943Y284987D03*
X146093D03*
X142943Y288987D03*
X146093D03*
Y292987D03*
X142943D03*
X141262Y300625D03*
X144412D03*
X138857Y310543D03*
X142007D03*
X139238Y327933D03*
X142388D03*
X138857Y323543D03*
X142007D03*
X138857Y319043D03*
X142007D03*
X138857Y314543D03*
X142007D03*
X139381Y332046D03*
X142531D03*
X144660Y407428D03*
X141510D03*
X144660Y411428D03*
X141510D03*
X136852Y513804D03*
X133702D03*
X137177Y738726D03*
X140327D03*
X137278Y725173D03*
X140428D03*
X137177Y730726D03*
X140327D03*
X137177Y734726D03*
X140327D03*
X137177Y742726D03*
X140327D03*
X153937Y12151D03*
X150787D03*
X150713Y17718D03*
X153863D03*
X153139Y55906D03*
X156289D03*
X152553Y74863D03*
X149403D03*
X164447Y432521D03*
X164245Y436834D03*
X164774Y441077D03*
Y445034D03*
X167597Y432521D03*
X167395Y436834D03*
X167924Y441077D03*
X173095Y444739D03*
X176245D03*
X167924Y445034D03*
X172654Y477790D03*
X175804D03*
X177038Y643933D03*
X173888D03*
X166388D03*
X169538D03*
X175619Y705976D03*
X172469D03*
X175619Y701976D03*
X172469D03*
X175619Y697976D03*
X172469D03*
X178289Y694040D03*
X175139D03*
X175619Y709976D03*
X172469D03*
X180078Y730521D03*
X176928D03*
X188261Y418925D03*
X185111D03*
X185117Y414885D03*
X188267D03*
X189173Y444392D03*
X186023D03*
X191163Y672526D03*
X194313D03*
X184312Y693887D03*
X187462D03*
X201995Y373701D03*
X198845D03*
X203584Y469953D03*
X200434D03*
Y474253D03*
X203584D03*
X207178Y576893D03*
X204028D03*
X207178Y572893D03*
X204028D03*
Y580893D03*
X207178D03*
Y584893D03*
X204028D03*
Y588893D03*
X207178D03*
X209299Y621977D03*
Y625977D03*
Y629977D03*
Y637977D03*
Y633977D03*
X208882Y671772D03*
X205732D03*
X212378Y596957D03*
X215528D03*
X212378Y600957D03*
X215528D03*
X212449Y621977D03*
Y625977D03*
Y629977D03*
Y637977D03*
Y633977D03*
X219229Y671772D03*
X222379D03*
X242631Y387964D03*
X238077Y439936D03*
X234927D03*
X233017Y671672D03*
X236167D03*
X245781Y387964D03*
X258477Y443592D03*
X255327D03*
X246816Y583156D03*
X243666D03*
X246816Y587156D03*
X243666D03*
X249349Y596382D03*
X246199D03*
X253796Y602262D03*
X256946D03*
X246475Y671772D03*
X249625D03*
X258991Y693945D03*
X255841D03*
X260110Y24932D03*
X263260D03*
X259673Y29229D03*
X262823D03*
X263352Y33472D03*
X260202D03*
X268483Y37453D03*
X271633D03*
X263352Y37429D03*
X260202D03*
X261754Y390871D03*
X264904D03*
X274625Y403203D03*
Y394703D03*
Y399203D03*
X273051Y656491D03*
Y652214D03*
Y648117D03*
Y664156D03*
X259895Y671772D03*
X263045D03*
X273051Y691038D03*
X285703Y6670D03*
X282553D03*
X278653Y6636D03*
X275503D03*
X284601Y36787D03*
X281451D03*
X277775Y403203D03*
Y394703D03*
Y399203D03*
X276201Y656491D03*
Y652214D03*
Y648117D03*
Y664156D03*
Y691038D03*
X285666Y717269D03*
X282516D03*
X301187Y398429D03*
X304337D03*
X294430Y471932D03*
X297580D03*
X294389Y476239D03*
X297539D03*
X301700Y597806D03*
X304850D03*
X302036Y623877D03*
X305186D03*
X300799Y717212D03*
X303949D03*
X296717Y721080D03*
X299867D03*
X316473Y295851D03*
X313323D03*
X313324Y303888D03*
X316474D03*
X313173Y307843D03*
X316323D03*
X316585Y299946D03*
X313435D03*
X319225Y326386D03*
X316075D03*
X316392Y338320D03*
X313242D03*
Y342418D03*
X316392D03*
Y354376D03*
X313242D03*
X316392Y358376D03*
X313242D03*
Y350376D03*
X316392D03*
X313242Y346376D03*
X316392D03*
X311015Y362506D03*
X314165D03*
X320130Y380571D03*
X316980D03*
X316963Y463789D03*
X320113D03*
X320106Y475619D03*
X316956D03*
X315513Y563003D03*
X318663D03*
X316957Y556488D03*
X320107D03*
X316957Y552188D03*
X320107D03*
X312065Y597255D03*
X315215D03*
X333005Y32331D03*
X329855D03*
X327058Y353801D03*
X330208D03*
X327008Y349221D03*
X330158D03*
X322599Y421643D03*
X325749D03*
Y429583D03*
X322599D03*
X325749Y425585D03*
X322599D03*
X325298Y536761D03*
X322949Y597198D03*
X326099D03*
X326723Y609480D03*
X323573D03*
X322949Y601121D03*
X326099D03*
X326628Y605364D03*
X323478D03*
X352578Y69305D03*
X346795Y299266D03*
X343645D03*
X342699Y312712D03*
X345849D03*
X343376Y308727D03*
X346526D03*
X345571Y322472D03*
X342421D03*
X339537Y424850D03*
X342687D03*
X351032Y424560D03*
X345750Y599212D03*
X348900D03*
X353667Y644166D03*
X366175Y15721D03*
X363025D03*
X355728Y69305D03*
X368743Y370508D03*
X354182Y424560D03*
X369484Y543467D03*
X356817Y644166D03*
X359105Y659130D03*
X355955D03*
X359103Y675130D03*
X355953D03*
X359105Y663128D03*
X355955D03*
X359085Y690624D03*
X355935D03*
X359103Y679133D03*
X355953D03*
X355955Y707128D03*
X359105D03*
Y703128D03*
X355955D03*
X359105Y699128D03*
X355955D03*
X359112Y695128D03*
X355962D03*
X360246Y723537D03*
X357096D03*
X359105Y711128D03*
X355955D03*
X369428Y723622D03*
X369336Y731459D03*
X357096Y735537D03*
X360246D03*
Y727537D03*
X357096D03*
X369336Y727459D03*
Y735459D03*
X360246Y739537D03*
X357096D03*
X369336Y739459D03*
X360246Y743537D03*
X357096D03*
X369336Y743459D03*
X374033Y17789D03*
X377183D03*
X371893Y370508D03*
X378061Y467075D03*
X374911D03*
X372634Y543467D03*
X376036Y547579D03*
X372886D03*
X376036Y551579D03*
X372886D03*
X370344Y658121D03*
X373494D03*
X370359Y654157D03*
X373509D03*
X370283Y650156D03*
X373433D03*
X370283Y646156D03*
X373433D03*
X370283Y666156D03*
X373433D03*
X370283Y670156D03*
X373433D03*
X370283Y674214D03*
X373433D03*
X370283Y678222D03*
X373433D03*
X370283Y686248D03*
X373433D03*
X370283Y690248D03*
X373433D03*
X370283Y682248D03*
X373433D03*
X370283Y702248D03*
X373433D03*
X370283Y706248D03*
X373433D03*
X370283Y698248D03*
X373433D03*
X370283Y694248D03*
X373433D03*
X384500Y715442D03*
X372578Y723622D03*
X372486Y731459D03*
Y727459D03*
Y735459D03*
Y739459D03*
Y743459D03*
X385724Y17519D03*
X388874D03*
X392789D03*
X395939D03*
X400589Y69610D03*
X390221Y69643D03*
X393371D03*
X400154Y532016D03*
X400064Y528015D03*
X400026Y524091D03*
X400037Y536127D03*
X400237Y540127D03*
X394293Y597942D03*
X397443D03*
X394599Y624109D03*
X397749D03*
X397743Y628233D03*
X394593D03*
X387650Y715442D03*
X403739Y69610D03*
X403304Y532016D03*
X403214Y528015D03*
X403176Y524091D03*
X416011Y550342D03*
X403187Y536127D03*
X403387Y540127D03*
X405831Y554402D03*
X408981D03*
X416040Y559017D03*
X416022Y554393D03*
X410348Y597288D03*
X407198D03*
X415542Y597300D03*
X416071Y609542D03*
X415542Y601257D03*
X416071Y605500D03*
X408163Y640872D03*
X411313D03*
X416504Y644754D03*
X416419Y652732D03*
Y656883D03*
Y648699D03*
Y673094D03*
Y669027D03*
Y677128D03*
Y681122D03*
X406646Y713835D03*
X403496D03*
X428204Y507319D03*
X431354D03*
X431006Y511581D03*
X427856D03*
X419161Y550342D03*
X419190Y559017D03*
X419172Y554393D03*
X424324Y566125D03*
X427474D03*
X431417Y587579D03*
X418692Y597300D03*
X419221Y609542D03*
X418692Y601257D03*
X425151Y604520D03*
X428301D03*
X432169D03*
X419221Y605500D03*
X428311Y640680D03*
X425161D03*
X419654Y644754D03*
X426270Y646100D03*
X429420D03*
X419569Y652732D03*
Y656883D03*
Y648699D03*
Y673094D03*
Y669027D03*
X422935Y685427D03*
X426085D03*
X419569Y677128D03*
Y681122D03*
X417427Y704664D03*
X420577D03*
Y696713D03*
X417427D03*
X420577Y700669D03*
X417427D03*
X447026Y184438D03*
X447760Y249404D03*
X447426Y245162D03*
Y241162D03*
Y237162D03*
X445190Y526518D03*
X448340D03*
X436290Y553337D03*
X439440D03*
X434567Y587579D03*
X435319Y604520D03*
X440040Y605071D03*
X443190D03*
X439642Y642843D03*
X442792D03*
X438863Y655595D03*
X442013D03*
Y651595D03*
X438863D03*
X439636Y646871D03*
X442786D03*
X442015Y667628D03*
X438865D03*
X442015Y671628D03*
X438865D03*
X442015Y675628D03*
X438865D03*
X442015Y679628D03*
X438865D03*
X461617Y74997D03*
X454582Y74774D03*
X457732D03*
X454433Y69194D03*
X457583D03*
X461791Y102736D03*
X458641D03*
X450176Y184438D03*
X450910Y249404D03*
X460351Y249696D03*
X457201D03*
X450576Y245162D03*
Y241162D03*
Y237162D03*
X450184Y257495D03*
X453334D03*
X456045Y513410D03*
X452895D03*
X452841Y532359D03*
X449691D03*
X449692Y538085D03*
X452842D03*
X456687Y543563D03*
X459837D03*
X459793Y539443D03*
X456643D03*
X463345Y581679D03*
X464767Y74997D03*
X467630Y98747D03*
X464480D03*
X467626Y94743D03*
X464476D03*
X470570Y163503D03*
X467420D03*
X470623Y157235D03*
X467473D03*
X466495Y581679D03*
X469992Y613207D03*
X466842D03*
X491304Y227953D03*
X488154D03*
X484992Y223746D03*
X488142D03*
X492157Y242877D03*
X495307D03*
X487013Y539525D03*
X483863D03*
X485465Y643604D03*
X488615D03*
X486806Y634796D03*
X483656D03*
X485363Y639623D03*
X488513D03*
X490623Y634603D03*
X493773D03*
X485465Y655604D03*
X488615D03*
X485465Y651604D03*
X488615D03*
Y647604D03*
X485465D03*
Y675604D03*
X488615D03*
X485465Y671604D03*
X488615D03*
X485465Y667604D03*
X488615D03*
X485465Y679628D03*
X488615D03*
X493447Y706582D03*
Y714582D03*
Y718582D03*
Y710582D03*
X496123Y230820D03*
X499273D03*
X505430Y436725D03*
X508580D03*
X497745Y449761D03*
X500895D03*
X497818Y445294D03*
X500968D03*
X509230Y441125D03*
X500763Y613598D03*
X503913D03*
X507551Y634818D03*
X504401D03*
Y638780D03*
X507551D03*
X498060Y660178D03*
X501210D03*
X500185Y650626D03*
X497035D03*
X500174Y646569D03*
X497024D03*
X496855Y687669D03*
X500005D03*
X496597Y706582D03*
Y714582D03*
Y718582D03*
Y710582D03*
X515780Y436725D03*
X512630D03*
X512380Y441125D03*
X515280Y609042D03*
X512130D03*
X521613Y615387D03*
X524763D03*
X516939Y634449D03*
X513789D03*
X541660Y211632D03*
X540132Y234993D03*
Y238993D03*
Y246993D03*
Y242993D03*
X535631Y624227D03*
X538781D03*
X535631Y620227D03*
X538781D03*
X544810Y211632D03*
X543282Y234993D03*
Y238993D03*
Y246993D03*
Y242993D03*
X548347Y274262D03*
X545197D03*
X550545Y292524D03*
X547395D03*
X550245Y296824D03*
X547095D03*
X550245Y301124D03*
X547095D03*
X553840Y439007D03*
X550690D03*
X550671Y443048D03*
X553821D03*
X550965Y460656D03*
X554115D03*
X550865Y456156D03*
X554015D03*
X548784Y617102D03*
X545634D03*
X572363Y103123D03*
X564984Y210682D03*
X561834D03*
X564984Y214682D03*
X561834D03*
X563615Y460956D03*
X560465D03*
X563515Y456156D03*
X560365D03*
X564213Y528325D03*
X561063D03*
X564213Y532225D03*
X561063D03*
Y524325D03*
X564213D03*
X568963Y545425D03*
X572113D03*
Y540825D03*
X568963D03*
Y552025D03*
X572113D03*
X569063Y559825D03*
X572213D03*
X568963Y555925D03*
X572113D03*
X568963Y567725D03*
X572113D03*
X568963Y571725D03*
X572113D03*
X568263Y575625D03*
X571413D03*
X568263Y579525D03*
X571413D03*
X568463Y591325D03*
X571613D03*
X568363Y583525D03*
X571513D03*
X568363Y587425D03*
X571513D03*
X575513Y103123D03*
X587043Y117732D03*
X587315Y121836D03*
X587043Y132232D03*
Y128232D03*
X586661Y171906D03*
X589811D03*
X586586Y179955D03*
X589736D03*
X586661Y175906D03*
X589811D03*
X585013Y540625D03*
X581863D03*
Y545225D03*
X585013D03*
X584413Y559445D03*
X581263D03*
X584483Y555235D03*
X581333D03*
X578873Y567253D03*
X582023D03*
X584736Y657848D03*
X581586D03*
X588768Y653385D03*
X584552Y686026D03*
X581402D03*
X584535Y690080D03*
X581385D03*
X584535Y694080D03*
X581385D03*
X603043Y104732D03*
X590193Y117732D03*
X590465Y121836D03*
X590193Y132232D03*
Y128232D03*
X598999Y236295D03*
X602149D03*
X599132Y271893D03*
X602282D03*
Y276393D03*
X599132D03*
X602976Y532108D03*
X599826D03*
Y544108D03*
X602976D03*
X599826Y540108D03*
X602976D03*
X599826Y536108D03*
X602976D03*
X599490Y578903D03*
X602640D03*
X599490Y574903D03*
X602640D03*
X599490Y582903D03*
X602640D03*
Y586903D03*
X599490D03*
X602607Y591105D03*
X599457D03*
X596512Y611545D03*
X593362D03*
X596512Y615545D03*
X593362D03*
X591918Y653385D03*
X610543Y104732D03*
X613693D03*
X618623Y104704D03*
X606193Y104732D03*
X610066Y261804D03*
X613216D03*
X610066Y257804D03*
X613216D03*
X618845Y402052D03*
Y398052D03*
X616829Y546764D03*
X619979D03*
X610044Y655572D03*
X606894D03*
Y650572D03*
X610044D03*
Y660572D03*
X606894D03*
X618059Y675183D03*
X614909D03*
X621773Y104704D03*
X633074Y132241D03*
X636224D03*
X634193Y289089D03*
X637343D03*
X626977Y292591D03*
X630127D03*
X634212Y285042D03*
X637362D03*
X630128Y296525D03*
X626978D03*
X626977Y288469D03*
X630127D03*
X631528Y387178D03*
X628378D03*
X633005Y383132D03*
X629855D03*
X621995Y402052D03*
Y398052D03*
X629708Y418774D03*
X626558D03*
X635286Y516730D03*
X632362Y568745D03*
X635512D03*
X645608Y288706D03*
X648758D03*
X648782Y284699D03*
X646013Y354885D03*
X642863D03*
X642963Y349785D03*
X646113D03*
X642114Y465888D03*
X638964D03*
Y461888D03*
X642114D03*
X638964Y457888D03*
X642114D03*
X638436Y516730D03*
X643012Y568745D03*
X639862D03*
X651226Y660492D03*
Y655072D03*
Y650072D03*
Y645072D03*
Y716674D03*
X648076D03*
X651226Y720674D03*
X648076D03*
X651226Y724674D03*
X648076D03*
X651226Y728674D03*
X648076D03*
X666336Y149428D03*
Y145428D03*
X666649Y164091D03*
Y160091D03*
X666313Y228335D03*
Y224335D03*
X666899Y242845D03*
Y238845D03*
X658272Y311365D03*
X655122D03*
X660861Y369552D03*
X664011D03*
X667861D03*
X654855Y470065D03*
X658005D03*
X657905Y487265D03*
X654755D03*
X657936Y482930D03*
X654786D03*
X657936Y478630D03*
X654786D03*
X658005Y491665D03*
X654855D03*
X661848Y617431D03*
X664998D03*
X654376Y660492D03*
Y655072D03*
Y650072D03*
Y645072D03*
X669486Y149428D03*
Y145428D03*
X669799Y164091D03*
Y160091D03*
X672020Y185259D03*
X675170D03*
X669463Y228335D03*
Y224335D03*
X670049Y242845D03*
Y238845D03*
X671011Y369552D03*
X678264Y369598D03*
X675114D03*
X672248Y532470D03*
X675398D03*
X678159Y519375D03*
X675009D03*
X672248Y540752D03*
X675398D03*
Y536752D03*
X672248D03*
Y544752D03*
X675398D03*
X672248Y548752D03*
X675398D03*
X693962Y145071D03*
X697112D03*
X693962Y149571D03*
X697112D03*
X698050Y216868D03*
X694900D03*
X698050Y221368D03*
X694900D03*
X707736Y513230D03*
X704586D03*
X712820Y513434D03*
X715970D03*
X701023Y549815D03*
X704173D03*
X703151Y535399D03*
X706301D03*
X731507Y460479D03*
X731670Y467368D03*
X731227Y500100D03*
X731425Y496000D03*
X731227Y504054D03*
X716586Y535030D03*
X719736D03*
X728875Y682700D03*
X725725D03*
X728975Y690800D03*
X725825D03*
X728875Y686700D03*
X725725D03*
X728975Y698800D03*
X725825D03*
X728975Y694800D03*
X725825D03*
X728975Y702800D03*
X725825D03*
X724325Y707800D03*
X727475D03*
X724325Y719800D03*
X727475D03*
X724325Y715800D03*
X727475D03*
X724325Y711800D03*
X727475D03*
X724325Y727800D03*
X727475D03*
X724325Y723800D03*
X727475D03*
X734657Y460479D03*
X734820Y467368D03*
X736954Y483641D03*
X740104D03*
X736976Y478975D03*
X740126D03*
X736925Y475000D03*
X740075D03*
X736835Y487639D03*
X739985D03*
X745075Y496800D03*
X741925D03*
X734377Y500100D03*
X741925Y501000D03*
X745075D03*
X734575Y496000D03*
X739425Y492500D03*
X742575D03*
X734377Y504054D03*
X737675Y641829D03*
X740825D03*
X737675Y653829D03*
X740825D03*
X737675Y649829D03*
X740825D03*
X737675Y645829D03*
X740825D03*
X754998Y446532D03*
X751848D03*
X754998Y455532D03*
X751848D03*
X754998Y451032D03*
X751848D03*
X755075Y475000D03*
X751925D03*
Y479000D03*
X755075D03*
X752075Y492500D03*
X748925D03*
Y488500D03*
X752075D03*
X761984Y559513D03*
X758834D03*
G54D132*
X412699Y466933D03*
X408369D03*
X412448Y471896D03*
Y476226D03*
G54D114*
X290490Y473703D03*
X600696Y612943D03*
X610796Y611219D03*
G54D123*
X354348Y38554D03*
X393718D03*
X712975Y155655D03*
Y165455D03*
Y173455D03*
Y183255D03*
Y234461D03*
Y244261D03*
Y252261D03*
Y262061D03*
X723275Y165455D03*
Y173455D03*
Y183255D03*
Y244261D03*
Y252261D03*
Y262061D03*
G54D105*
X210709Y541953D03*
G36*
G01X-32014Y133813D02*
Y131402D01*
G02X-33794Y130113I-858J-689D01*
G01X-34950D01*
G02X-36794I-922J600D01*
G01X-37950D01*
G02X-39730Y131402I-922J600D01*
G01Y133813D01*
X-38130D01*
Y132113D01*
X-33614D01*
Y133813D01*
X-32014D01*
G37*
G36*
G01Y241133D02*
Y238722D01*
G02X-33794Y237433I-858J-689D01*
G01X-34950D01*
G02X-36794I-922J600D01*
G01X-37950D01*
G02X-39730Y238722I-922J600D01*
G01Y241133D01*
X-38130D01*
Y239433D01*
X-33614D01*
Y241133D01*
X-32014D01*
G37*
G54D142*
X447355Y157140D03*
Y177140D03*
X461921Y157140D03*
Y177140D03*
G54D133*
X417659Y485373D03*
Y490373D03*
Y495373D03*
Y500373D03*
X441359Y485373D03*
Y500373D03*
Y495373D03*
Y490373D03*
G54D160*
X557207Y235893D03*
Y270863D03*
X572955Y235893D03*
X571380D03*
X569805D03*
X568231D03*
X566656D03*
X565081D03*
X563506D03*
X561931D03*
X560357D03*
X558782D03*
Y270863D03*
X560357D03*
X561931D03*
X563506D03*
X565081D03*
X566656D03*
X568231D03*
X569805D03*
X571380D03*
X572955D03*
X585553Y235893D03*
X583979D03*
X582404D03*
X580829D03*
X579254D03*
X577679D03*
X576105D03*
X574530D03*
Y270863D03*
X576105D03*
X577679D03*
X579254D03*
X580829D03*
X582404D03*
X583979D03*
X585553D03*
G54D40*
X58466Y293171D03*
X66892D03*
X83475Y279475D03*
X95060Y159811D03*
X91320Y167685D03*
X98800D03*
X87215Y271601D03*
X90955Y279475D03*
X142500Y460406D03*
X138760Y468280D03*
X146240D03*
X146364Y726705D03*
X150104Y734579D03*
X153844Y726705D03*
X238069Y633421D03*
X234329Y641295D03*
X241809D03*
X258553Y438319D03*
X254813Y430445D03*
X262293D03*
X321514Y415629D03*
X325254Y407755D03*
X328994Y415629D03*
X369934Y326749D03*
X377414D03*
X373674Y334623D03*
X698881Y529230D03*
X716021Y521256D03*
X712281Y529130D03*
X702621Y521356D03*
X706361Y529230D03*
X719761Y529130D03*
G54D124*
X352079Y382282D03*
X347079D03*
Y408896D03*
X352079D03*
X362079Y382282D03*
X357079D03*
Y408896D03*
X362079D03*
G54D22*
X22935Y602945D03*
Y599795D03*
X18603Y611764D03*
Y614914D03*
X27018Y13036D03*
Y16186D03*
X37599Y44149D03*
X33677Y34564D03*
Y37714D03*
X37599Y47299D03*
X34140Y547324D03*
Y544174D03*
X30140Y547324D03*
Y544174D03*
X26145Y547371D03*
Y544221D03*
X32270Y608415D03*
Y605265D03*
X28270Y608415D03*
Y605265D03*
X41599Y44149D03*
X45578D03*
X49559D03*
X41599Y47299D03*
X45578D03*
X49559D03*
X46981Y65593D03*
Y62443D03*
X50981Y65593D03*
Y62443D03*
X54703Y115946D03*
Y119096D03*
X46811Y115664D03*
Y118814D03*
X50906Y510709D03*
Y513859D03*
X51337Y526060D03*
Y522910D03*
X46140Y547324D03*
Y544174D03*
X50140D03*
Y547324D03*
X44270Y608415D03*
Y605265D03*
X48270D03*
Y608415D03*
X66981Y65593D03*
Y62443D03*
X62981D03*
Y65593D03*
X54981D03*
Y62443D03*
X67831Y145032D03*
Y141882D03*
X61022Y180712D03*
Y183862D03*
X65169Y183921D03*
Y180771D03*
X60729Y204326D03*
Y207476D03*
X64906Y207595D03*
Y204445D03*
X60032Y228683D03*
Y231833D03*
X60182Y249949D03*
X60177Y246022D03*
Y242872D03*
X60029Y235880D03*
Y239030D03*
X60182Y253099D03*
X55351Y522907D03*
Y526057D03*
X59299Y529203D03*
Y526053D03*
X79360Y43076D03*
Y39926D03*
X70745Y170036D03*
X71730Y180744D03*
Y177594D03*
X70745Y173186D03*
X71778Y212026D03*
Y215176D03*
X71758Y218914D03*
Y222064D03*
X80369Y250679D03*
X80391Y243309D03*
Y246459D03*
X80369Y253829D03*
X72368Y290582D03*
Y293732D03*
X82368D03*
Y290582D03*
X75573Y503994D03*
Y507144D03*
X80368Y509170D03*
Y506020D03*
X84103Y509161D03*
X99968Y371107D03*
Y374257D03*
X95968Y371107D03*
Y374257D03*
X91458Y509198D03*
Y506048D03*
X102257Y172049D03*
Y175199D03*
X113620Y398184D03*
Y401334D03*
X109342Y413499D03*
Y410349D03*
X112072Y483758D03*
Y486908D03*
X108026Y486861D03*
Y483711D03*
X114372Y512558D03*
Y515708D03*
X109972Y512558D03*
Y515708D03*
X126072Y483758D03*
Y486908D03*
X129607Y689212D03*
Y692362D03*
X146380Y27366D03*
Y24216D03*
X137009Y32160D03*
Y35310D03*
X145210Y54510D03*
Y57660D03*
X149157Y57580D03*
Y54430D03*
X141160Y57630D03*
Y54480D03*
X137704Y408853D03*
Y412003D03*
X137759Y689175D03*
Y681175D03*
Y684325D03*
X133607Y689212D03*
X137759Y692325D03*
X133607Y692362D03*
X158181Y14450D03*
Y17600D03*
X154592Y24216D03*
Y27366D03*
X150592D03*
Y24216D03*
X158165Y27522D03*
X163933Y37475D03*
Y34325D03*
X160111Y56721D03*
X151101Y445079D03*
Y441929D03*
X151145Y463434D03*
Y466584D03*
X162663Y575608D03*
Y572458D03*
X158430Y575710D03*
Y572560D03*
X157963Y636958D03*
Y640108D03*
X164812Y666374D03*
Y669524D03*
X175335Y14913D03*
Y18063D03*
X171254Y14872D03*
Y18022D03*
X179361Y401571D03*
Y404721D03*
X167861Y424146D03*
X171993Y420771D03*
Y417621D03*
X175993D03*
Y420771D03*
X179544Y421477D03*
X167861Y427296D03*
X166646Y484538D03*
Y487688D03*
X179263Y575708D03*
Y572558D03*
X170930Y575710D03*
Y572560D03*
X166663Y575608D03*
Y572458D03*
X175263Y575708D03*
Y572558D03*
X172455Y732775D03*
Y735925D03*
X183419Y397314D03*
Y394164D03*
X183361Y401571D03*
Y404721D03*
X191803Y433565D03*
Y436715D03*
X196410Y643700D03*
X191910D03*
X187410D03*
X196410Y653700D03*
Y656850D03*
X187410Y653700D03*
Y656850D03*
X196410Y646850D03*
X191910D03*
X187410D03*
X189940Y715931D03*
Y719081D03*
X185440Y715931D03*
Y719081D03*
X194440Y715898D03*
Y719048D03*
Y739081D03*
Y727581D03*
Y730731D03*
X189940Y727581D03*
Y730731D03*
X185440Y727581D03*
Y730731D03*
X189940Y739081D03*
X185440D03*
X194440Y742231D03*
X189940D03*
X185440D03*
X211660Y391753D03*
Y388603D03*
X208729Y379173D03*
Y382323D03*
X211700Y398689D03*
Y395539D03*
X202009Y465628D03*
Y462478D03*
X205410Y643700D03*
X200910D03*
X205410Y653700D03*
Y656850D03*
X200910Y653700D03*
Y656850D03*
X205410Y646850D03*
X200910D03*
X198940Y715931D03*
Y719081D03*
X207940Y715931D03*
Y719081D03*
X203440Y715898D03*
Y719048D03*
X207940Y739081D03*
X203440D03*
X198940D03*
X207940Y727581D03*
Y730731D03*
X203440Y727581D03*
Y730731D03*
X198940Y727581D03*
Y730731D03*
X207940Y742231D03*
X203440D03*
X198940D03*
X212729Y379173D03*
Y382323D03*
X216729Y379173D03*
Y382323D03*
X220729Y379173D03*
Y382323D03*
X224729Y379173D03*
Y382323D03*
X221228Y396690D03*
Y393540D03*
X225228Y396690D03*
Y393540D03*
X223953Y469967D03*
Y466817D03*
X219640Y479308D03*
Y476158D03*
X221129Y639089D03*
Y635939D03*
X225179Y639089D03*
Y635939D03*
X221440Y739081D03*
X225940Y727581D03*
Y730731D03*
X212440Y739081D03*
X216940D03*
X212440Y730731D03*
Y727581D03*
X225940Y739081D03*
X221440Y730731D03*
Y727581D03*
X216940Y730731D03*
Y727581D03*
X221440Y742231D03*
X212440D03*
X216940D03*
X225940D03*
X232729Y382323D03*
Y379173D03*
X228729Y382323D03*
Y379173D03*
X236729Y382323D03*
Y379173D03*
X240729Y382323D03*
Y379173D03*
X228242Y469924D03*
Y466774D03*
X242009Y466578D03*
Y469728D03*
X237609Y466578D03*
Y469728D03*
X233309Y466578D03*
Y469728D03*
X241909Y478128D03*
Y474978D03*
X237609Y478128D03*
Y474978D03*
X233309Y478128D03*
Y474978D03*
X229199Y635939D03*
Y639089D03*
X229584Y649349D03*
Y646199D03*
X237451D03*
Y649349D03*
X241670Y649253D03*
Y646103D03*
X233584Y649349D03*
Y646199D03*
X234940Y727581D03*
Y730731D03*
X239440Y739081D03*
X230440D03*
X239440Y730731D03*
Y727581D03*
X234940Y739081D03*
X230440Y730731D03*
Y727581D03*
X239440Y742231D03*
X230440D03*
X234940D03*
X253511Y60208D03*
Y57058D03*
X244729Y379173D03*
Y382323D03*
X248729Y379173D03*
Y382323D03*
X252729D03*
Y379173D03*
X256729D03*
Y382323D03*
X254798Y420929D03*
Y424079D03*
X258798Y420929D03*
Y424079D03*
X251309Y466078D03*
Y469228D03*
X255509Y465978D03*
Y469128D03*
X246109Y478128D03*
Y474978D03*
X255509Y478128D03*
Y474978D03*
X251309Y478128D03*
Y474978D03*
X257109Y582978D03*
Y586128D03*
X246313Y632759D03*
Y629609D03*
X246293Y645233D03*
Y648383D03*
X257440Y739081D03*
X252940Y727581D03*
Y730731D03*
X243940Y727581D03*
Y730731D03*
X248440Y739081D03*
Y730731D03*
Y727581D03*
X252940Y739081D03*
X257440Y730731D03*
Y727581D03*
X243940Y739081D03*
X257440Y742231D03*
X248440D03*
X252940D03*
X243940D03*
X267421Y13166D03*
Y10016D03*
X271421D03*
Y13166D03*
X274972Y13872D03*
X263289Y19691D03*
Y16541D03*
X267987Y68029D03*
Y71179D03*
X271987Y68029D03*
Y71179D03*
X260729Y379173D03*
Y382323D03*
X272729Y379173D03*
Y382323D03*
X264729D03*
Y379173D03*
X268729Y382323D03*
Y379173D03*
X262798Y420929D03*
Y424079D03*
X266732Y420093D03*
Y416943D03*
X260609Y465978D03*
Y469128D03*
Y478128D03*
Y474978D03*
X269109Y478128D03*
Y474978D03*
X273809Y582978D03*
Y586128D03*
X269609Y582978D03*
Y586128D03*
X261940Y739081D03*
X266440D03*
X270940D03*
X266440Y730731D03*
Y727581D03*
X270940Y730731D03*
Y727581D03*
X261940Y730731D03*
Y727581D03*
Y742231D03*
X266440D03*
X270940D03*
X287233Y25708D03*
Y28858D03*
X275987Y68029D03*
Y71179D03*
X283987Y68029D03*
Y71179D03*
X279987Y68029D03*
Y71179D03*
X287987Y68029D03*
Y71179D03*
X289142Y372173D03*
Y369023D03*
X288729Y382323D03*
Y379173D03*
X280729D03*
Y382323D03*
X276729Y379173D03*
Y382323D03*
X284729D03*
Y379173D03*
X286710Y398785D03*
Y395635D03*
X276347Y448426D03*
Y451576D03*
X278109Y582978D03*
Y586128D03*
X282309Y582978D03*
Y586128D03*
X275440Y739081D03*
X279940Y727581D03*
Y730731D03*
X284440Y739081D03*
X288940Y727581D03*
Y730731D03*
X275440D03*
Y727581D03*
X279940Y739081D03*
X288940D03*
X284440Y730731D03*
Y727581D03*
X275440Y742231D03*
X284440D03*
X279940D03*
X288940D03*
X305142Y372173D03*
Y369023D03*
X297142Y372173D03*
Y369023D03*
X293142Y372173D03*
Y369023D03*
X301142Y372173D03*
Y369023D03*
X292729Y382323D03*
Y379173D03*
X298972Y608639D03*
Y605489D03*
X302440Y739081D03*
X297940Y727581D03*
Y730731D03*
X293440Y739081D03*
X297940D03*
X293440Y730731D03*
Y727581D03*
X302440Y742231D03*
X293440D03*
X297940D03*
X316466Y68029D03*
Y71179D03*
X312466Y68029D03*
Y71179D03*
X308466Y68029D03*
Y71179D03*
X320466Y68029D03*
Y71179D03*
X320374Y292653D03*
Y295803D03*
X314640Y319227D03*
Y316077D03*
X318640Y319227D03*
Y316077D03*
X310640Y319227D03*
Y316077D03*
X321110Y334011D03*
Y330861D03*
X309142Y369023D03*
Y372173D03*
X312824Y387863D03*
Y391013D03*
X313222Y378983D03*
Y382133D03*
X316938Y407069D03*
Y410219D03*
X319135Y594112D03*
Y597262D03*
X318880Y621427D03*
Y624577D03*
X314910D03*
Y621427D03*
X311329Y620721D03*
X314848Y636418D03*
Y639568D03*
X307574Y636613D03*
Y639763D03*
X314940Y719731D03*
Y716581D03*
X311440Y739081D03*
X320440D03*
X315940D03*
X306940Y727581D03*
Y730731D03*
X311440D03*
Y727581D03*
X320440Y730731D03*
Y727581D03*
X315940Y730731D03*
Y727581D03*
X306940Y739081D03*
X311440Y742231D03*
X320440D03*
X315940D03*
X306940D03*
X324466Y68029D03*
Y71179D03*
X324441Y295764D03*
Y292614D03*
X332348Y307752D03*
Y310902D03*
X322640Y319227D03*
Y316077D03*
X326640Y319227D03*
Y316077D03*
X330640Y319227D03*
Y316077D03*
X325700Y327721D03*
Y337951D03*
Y334801D03*
Y330871D03*
X331302Y429920D03*
Y426770D03*
X337012Y509444D03*
Y506294D03*
X332512Y509444D03*
Y506294D03*
X327739Y509656D03*
Y506506D03*
X336688Y537828D03*
Y540978D03*
X332088Y541078D03*
Y537928D03*
X336267Y572677D03*
Y569527D03*
X323036Y614013D03*
Y617163D03*
X323583Y636439D03*
Y639589D03*
X322940Y719731D03*
Y716581D03*
X324940Y739081D03*
X333940D03*
X329440D03*
X324940Y730731D03*
Y727581D03*
X333940Y730731D03*
Y727581D03*
X329440Y730731D03*
Y727581D03*
X324940Y742231D03*
X333940D03*
X329440D03*
X349490Y60647D03*
Y63797D03*
X341512Y509444D03*
Y506294D03*
X346012Y509444D03*
Y506294D03*
X350512Y509444D03*
Y506294D03*
X340388Y569570D03*
Y572720D03*
X347606Y713349D03*
Y710199D03*
X346940Y739081D03*
X342940Y727581D03*
Y730731D03*
X338440Y739081D03*
X351940Y727581D03*
Y730731D03*
X342940Y739081D03*
X347440Y730731D03*
Y727581D03*
X338440Y730731D03*
Y727581D03*
X350940Y739081D03*
X346940Y742231D03*
X338440D03*
X342940D03*
X350940D03*
X358940Y60647D03*
Y63797D03*
X365026Y329623D03*
Y326473D03*
X358210Y446344D03*
Y449494D03*
X368943Y509323D03*
Y512473D03*
X368238Y516378D03*
Y519528D03*
X365433Y540086D03*
Y543236D03*
X361433Y540086D03*
Y543236D03*
X367477Y627663D03*
Y630813D03*
X379051Y60991D03*
X370053Y60823D03*
X379051Y64141D03*
X370053Y63973D03*
X374207Y473374D03*
Y476524D03*
X374203Y484874D03*
Y488024D03*
X380786Y514797D03*
Y517947D03*
X380699Y546576D03*
X386999Y61186D03*
X395080Y61360D03*
X386999Y64336D03*
X395080Y64510D03*
X395656Y516297D03*
X399837D03*
X387221Y531263D03*
Y534413D03*
X395656Y519447D03*
X399837D03*
X391559Y609125D03*
Y605975D03*
X386464Y640267D03*
Y637117D03*
X390482D03*
Y640267D03*
X411608Y514020D03*
Y510870D03*
X406150Y513960D03*
X411834Y548430D03*
Y545280D03*
X407834D03*
Y548430D03*
X415605Y615038D03*
Y618188D03*
X411473Y621563D03*
Y624713D03*
X407473D03*
Y621563D03*
X403922Y620857D03*
X423845Y550973D03*
Y554123D03*
X428039Y550949D03*
Y554099D03*
X428060Y559112D03*
Y562262D03*
X423829Y559032D03*
Y562182D03*
X432152Y559098D03*
Y562248D03*
X432351Y550933D03*
Y554083D03*
X417781Y689290D03*
Y686140D03*
X418440Y739081D03*
X430940D03*
X426440D03*
X421940Y727581D03*
Y730731D03*
X422440Y739081D03*
X430940Y730731D03*
Y727581D03*
X426440Y730731D03*
Y727581D03*
X418440Y742231D03*
X430940D03*
X426440D03*
X422440D03*
X446304Y71848D03*
Y74998D03*
X439749Y509637D03*
Y512787D03*
X443768Y518161D03*
X439762Y518106D03*
X447758Y518161D03*
X443845Y509635D03*
Y512785D03*
X445729Y534196D03*
Y531046D03*
X441651Y534276D03*
Y531126D03*
X443768Y521311D03*
X439762Y521256D03*
X447758Y521311D03*
X443028Y543127D03*
Y546277D03*
X446334Y546499D03*
X446536Y553518D03*
Y550368D03*
X436219Y559133D03*
Y562283D03*
X442207Y629045D03*
Y632195D03*
X443940Y739081D03*
X448440Y727581D03*
Y730731D03*
X439940Y739081D03*
X435440D03*
X448440D03*
X435440Y730731D03*
Y727581D03*
X439940Y730731D03*
Y727581D03*
X443940Y742231D03*
X439940D03*
X435440D03*
X448440D03*
X450682Y71690D03*
Y74840D03*
X452115Y191819D03*
Y188669D03*
X450937Y486264D03*
Y489414D03*
X460722Y532351D03*
X456722D03*
X450367Y546436D03*
Y543286D03*
X460722Y535501D03*
X456722D03*
X450790Y553519D03*
Y550369D03*
X461588Y550463D03*
Y553613D03*
X451940Y689081D03*
X461440D03*
X456440D03*
X451940Y692231D03*
X461440D03*
X456440D03*
X452940Y739081D03*
X457440Y727581D03*
Y730731D03*
X461940Y739081D03*
X457440D03*
X452940Y742231D03*
X461940D03*
X457440D03*
X470623Y154085D03*
Y157235D03*
X471221Y194784D03*
Y197934D03*
X465291Y537985D03*
Y534835D03*
X478411Y597114D03*
Y593964D03*
X474397D03*
Y597114D03*
X474884Y607476D03*
Y604326D03*
X473436Y626379D03*
Y629529D03*
X469444Y629940D03*
Y633090D03*
X465940Y689081D03*
X470440D03*
X474940D03*
X465940Y692231D03*
X470440D03*
X474940D03*
X470940Y739081D03*
X474940D03*
X466440Y727581D03*
Y730731D03*
X470430Y730748D03*
Y727598D03*
X474930Y730748D03*
Y727598D03*
X479430Y730748D03*
Y727598D03*
X466440Y739081D03*
X478940D03*
X470940Y742231D03*
X474940D03*
X466440D03*
X478940D03*
X488438Y103048D03*
Y106198D03*
X483538Y103048D03*
Y106198D03*
X492955Y106179D03*
Y103029D03*
X495276Y198703D03*
Y195553D03*
X491171Y195574D03*
Y198724D03*
X484280Y195416D03*
Y198566D03*
X485719Y276271D03*
Y279421D03*
X494238Y603450D03*
Y606600D03*
X487240Y739081D03*
X491540D03*
X482940D03*
X492440Y730731D03*
Y727581D03*
X487940Y730731D03*
Y727581D03*
X483440Y730731D03*
Y727581D03*
X487240Y742231D03*
X491540D03*
X482940D03*
X508955Y106179D03*
Y103029D03*
X496955Y106179D03*
Y103029D03*
X504955Y106179D03*
Y103029D03*
X500955Y106179D03*
Y103029D03*
X508300Y201875D03*
Y198725D03*
X504052Y202146D03*
Y205296D03*
X507638Y522050D03*
Y525200D03*
X502038Y525900D03*
Y522750D03*
X502238Y603450D03*
Y606600D03*
X498238Y603450D03*
Y606600D03*
X500140Y739081D03*
X504140D03*
X495840D03*
X504940Y727581D03*
Y730731D03*
X509670Y730633D03*
Y727483D03*
X508140Y739081D03*
X496940Y730731D03*
Y727581D03*
X500140Y742231D03*
X504140D03*
X495840D03*
X508140D03*
X520955Y106179D03*
Y103029D03*
X516955Y106179D03*
Y103029D03*
X512955Y106179D03*
Y103029D03*
X524955Y106179D03*
Y103029D03*
X516657Y200990D03*
X520500Y200925D03*
X524500D03*
X512200Y198625D03*
Y201775D03*
X512160Y211450D03*
Y214600D03*
X516657Y204140D03*
X520500Y204075D03*
X524500D03*
X521800Y214675D03*
Y211525D03*
X513500Y221468D03*
Y224618D03*
X519675Y238308D03*
Y241458D03*
X515675Y238308D03*
Y241458D03*
X524675D03*
Y238308D03*
X526440Y425081D03*
Y428231D03*
X519840Y430981D03*
Y434131D03*
X526440Y437731D03*
Y434581D03*
X525474Y512154D03*
Y515304D03*
X526638Y611200D03*
Y608050D03*
X518940Y726981D03*
Y730131D03*
X520940Y739081D03*
X523940Y727581D03*
Y730731D03*
X512140Y739081D03*
X514940Y727581D03*
Y730731D03*
X516940Y739081D03*
X525440D03*
X520940Y742231D03*
X512140D03*
X516940D03*
X525440D03*
X536955Y103029D03*
Y106179D03*
X532955D03*
Y103029D03*
X528955Y106179D03*
Y103029D03*
X532500Y200925D03*
X540500D03*
X528500D03*
X536657Y200990D03*
X532500Y204075D03*
X531929Y216238D03*
Y219388D03*
X535929Y216238D03*
Y219388D03*
X540500Y204075D03*
X528500D03*
X536657Y204140D03*
X530940Y425081D03*
Y428231D03*
X540940Y425081D03*
Y428231D03*
X535940Y425081D03*
Y428231D03*
X541440Y437731D03*
Y434581D03*
X536440Y437731D03*
Y434581D03*
X531440Y437731D03*
Y434581D03*
X529474Y512154D03*
Y515304D03*
X542438Y607850D03*
Y611000D03*
X534638Y607950D03*
Y611100D03*
X530738D03*
Y607950D03*
X536068Y629326D03*
Y632476D03*
X541440Y716168D03*
Y713018D03*
X531570Y716345D03*
Y713195D03*
X541940Y739081D03*
X532940Y727581D03*
Y730731D03*
X529940Y739081D03*
X534440D03*
X541940Y730731D03*
Y727581D03*
X528440Y730731D03*
Y727581D03*
X541940Y742231D03*
X529940D03*
X534440D03*
X547248Y103161D03*
Y100011D03*
X555938Y100048D03*
Y103198D03*
X551454D03*
Y100048D03*
X553909Y201089D03*
X549909D03*
X557909D03*
X544500Y200925D03*
X553909Y204239D03*
X549909D03*
X557909D03*
X544500Y204075D03*
X545940Y425081D03*
Y428231D03*
X549940Y425081D03*
Y428231D03*
X555140Y448752D03*
Y451902D03*
X551140D03*
Y448752D03*
X546938Y607850D03*
Y611000D03*
X543400Y632456D03*
Y629306D03*
X549940Y716168D03*
Y713018D03*
X546440Y739081D03*
X550940D03*
X555440D03*
X546440Y730731D03*
Y727581D03*
X550940Y730731D03*
Y727581D03*
X555440Y730731D03*
Y727581D03*
X546440Y742231D03*
X550940D03*
X555440D03*
X565938Y100048D03*
Y103198D03*
X561909Y201089D03*
Y204239D03*
X564354Y286277D03*
Y283127D03*
X559140Y448752D03*
Y451902D03*
X562812Y627509D03*
Y630659D03*
X565074Y716168D03*
Y713018D03*
X564440Y727581D03*
Y730731D03*
X568940Y739081D03*
X573440Y727581D03*
Y730731D03*
X559940Y739081D03*
X573440D03*
X568940Y730731D03*
Y727581D03*
X564440Y739081D03*
X559940Y730731D03*
Y727581D03*
X568940Y742231D03*
X559940D03*
X573440D03*
X564440D03*
X586842Y155799D03*
X586769Y166461D03*
Y163311D03*
X586842Y158949D03*
X587707Y226968D03*
Y223818D03*
X579707Y226968D03*
Y223818D03*
X583707Y226968D03*
Y223818D03*
X589107Y289518D03*
Y292668D03*
X588437Y564120D03*
Y560970D03*
X586369Y590017D03*
Y593167D03*
X578399Y589937D03*
Y593087D03*
X582399Y589937D03*
Y593087D03*
X582620Y625963D03*
Y622813D03*
X589800Y683909D03*
Y687059D03*
X583440Y739081D03*
X587940Y727581D03*
Y730731D03*
Y739081D03*
X583440Y730731D03*
Y727581D03*
Y742231D03*
X587940D03*
X590842Y155799D03*
X590769Y166461D03*
Y163311D03*
X590842Y158949D03*
X590598Y202307D03*
Y205457D03*
X591707Y226968D03*
Y223818D03*
X595707Y226968D03*
Y223818D03*
X593107Y289518D03*
Y292668D03*
X604338Y344760D03*
Y341610D03*
X604091Y352754D03*
Y349604D03*
X604493Y361140D03*
Y357990D03*
X596437Y564120D03*
Y560970D03*
X600437Y564120D03*
Y560970D03*
X604437Y564120D03*
Y560970D03*
X592437Y564120D03*
Y560970D03*
X596940Y727581D03*
Y730731D03*
X601440Y739081D03*
X605940D03*
X592440D03*
Y730731D03*
Y727581D03*
X601440Y730731D03*
Y727581D03*
X605940Y730731D03*
Y727581D03*
X596940Y739081D03*
X601440Y742231D03*
X605940D03*
X592440D03*
X596940D03*
X620366Y292625D03*
X611988Y407850D03*
X615928D03*
X611988Y411000D03*
X615928D03*
X614338Y418820D03*
Y415670D03*
X618368Y418830D03*
Y415680D03*
X612937Y564320D03*
Y561170D03*
X617437Y564320D03*
Y561170D03*
X608437Y564120D03*
Y560970D03*
X611249Y633125D03*
Y636275D03*
X619302Y633065D03*
Y636215D03*
X607292Y681400D03*
Y678250D03*
X617242Y682697D03*
Y679547D03*
X606972Y688804D03*
Y691954D03*
X613882Y691668D03*
Y694818D03*
X614172Y705076D03*
Y701926D03*
X610172Y705076D03*
Y701926D03*
X610440Y739081D03*
X614940D03*
X619440D03*
X614940Y730731D03*
Y727581D03*
X619440Y730731D03*
Y727581D03*
X610440Y730731D03*
Y727581D03*
Y742231D03*
X614940D03*
X619440D03*
X627369Y300555D03*
Y303705D03*
X621937Y564320D03*
Y561170D03*
X630137Y633742D03*
Y636892D03*
X634137Y633742D03*
Y636892D03*
X628440Y739081D03*
X633130Y738905D03*
X637130D03*
X623940Y739081D03*
X628440Y730731D03*
Y727581D03*
X623940Y730731D03*
Y727581D03*
X628440Y742231D03*
X633130Y742055D03*
X637130D03*
X623940Y742231D03*
X643957Y47525D03*
Y50675D03*
X639957Y47525D03*
Y50675D03*
X645236Y371027D03*
Y367877D03*
X641236Y371027D03*
Y367877D03*
X649236Y371027D03*
Y367877D03*
X651437Y575720D03*
Y572570D03*
X642737Y633842D03*
Y636992D03*
X646737Y633842D03*
Y636992D03*
X650970Y633740D03*
Y636890D03*
X638470Y633740D03*
Y636890D03*
X643500Y738925D03*
Y742075D03*
X655947Y47606D03*
Y50756D03*
X659947Y47606D03*
Y50756D03*
X653352Y285183D03*
Y288333D03*
X653938Y367910D03*
Y371060D03*
X668573Y517014D03*
X664024Y516991D03*
X659933Y517197D03*
X668573Y520164D03*
X664024Y520141D03*
X659933Y520347D03*
X655170Y633840D03*
Y636990D03*
X664870Y673830D03*
Y669424D03*
Y666274D03*
Y676980D03*
X659678Y684907D03*
Y688057D03*
X660660Y742510D03*
Y739360D03*
X654660Y742510D03*
Y739360D03*
X669987Y47536D03*
Y50686D03*
X675927Y47536D03*
Y50686D03*
X679927Y47536D03*
Y50686D03*
X672306Y527718D03*
Y524568D03*
X691161Y512755D03*
Y515905D03*
X686661Y512755D03*
Y515905D03*
X693966Y523712D03*
Y520562D03*
X707176Y43845D03*
X711676D03*
X707176Y46995D03*
X711676D03*
X709400Y743375D03*
Y740225D03*
X713400Y743375D03*
Y740225D03*
X731566Y452628D03*
Y455778D03*
Y445468D03*
Y448618D03*
X726829Y515757D03*
Y512607D03*
X722383Y515757D03*
Y512607D03*
X729400Y743375D03*
Y740225D03*
X721400Y743375D03*
Y740225D03*
X717400Y743375D03*
Y740225D03*
X725400Y743375D03*
Y740225D03*
G36*
G01X-39730Y745893D02*
Y748304D01*
G02X-37950Y749593I858J689D01*
G01X-36794D01*
G02X-34950I922J-600D01*
G01X-33794D01*
G02X-32014Y748304I922J-600D01*
G01Y745893D01*
X-33614D01*
Y747593D01*
X-38130D01*
Y745893D01*
X-39730D01*
G37*
G54D151*
X507489Y281538D03*
G54D31*
X47292Y422630D03*
Y441446D03*
X72488Y422630D03*
Y441446D03*
X439566Y418705D03*
Y438705D03*
X464762Y418705D03*
Y438705D03*
G54D106*
X208430Y599735D03*
X198210Y601459D03*
X595294Y260495D03*
X605890Y258785D03*
X625835Y400347D03*
X637543Y399147D03*
G54D115*
X287709Y483619D03*
G54D23*
X36900Y12883D03*
X34341D03*
X31782D03*
Y20757D03*
X34341D03*
X36900D03*
G54D125*
X384758Y645239D03*
Y647739D03*
Y650239D03*
Y652739D03*
Y655239D03*
Y657739D03*
Y660239D03*
Y662739D03*
Y667942D03*
Y670442D03*
Y672942D03*
Y675442D03*
Y677942D03*
Y680442D03*
Y682942D03*
Y685442D03*
X406358Y660239D03*
Y657739D03*
Y655239D03*
Y652739D03*
Y650239D03*
Y647739D03*
Y645239D03*
Y662739D03*
Y675442D03*
Y672942D03*
Y670442D03*
Y667942D03*
Y685442D03*
Y682942D03*
Y680442D03*
Y677942D03*
G54D41*
X71970Y357848D03*
X105613Y147532D03*
X147590Y647878D03*
X487770Y513674D03*
X577880Y395242D03*
X693400Y758198D03*
X745580Y62870D03*
G54D32*
X45220Y471985D03*
X45546Y488556D03*
X45330Y480233D03*
X56820Y471985D03*
X57146Y488556D03*
X56930Y480233D03*
X143823Y687539D03*
X155423D03*
X195809Y450491D03*
X184209D03*
X291237Y42886D03*
X279637D03*
X291237Y51290D03*
X279637D03*
X295064Y591707D03*
X306664D03*
X387657Y591843D03*
X399257D03*
G54D116*
X284428Y654034D03*
Y656002D03*
Y657971D03*
Y659939D03*
Y661908D03*
Y663876D03*
Y665845D03*
Y667813D03*
Y669782D03*
Y671750D03*
Y673719D03*
Y675688D03*
Y677656D03*
Y679624D03*
Y681593D03*
Y683562D03*
Y685530D03*
Y687499D03*
Y689467D03*
Y691436D03*
Y693404D03*
Y695373D03*
Y697341D03*
Y699310D03*
Y701278D03*
X345452Y659939D03*
Y657971D03*
Y656002D03*
Y654034D03*
Y675688D03*
Y673719D03*
Y671750D03*
Y669782D03*
Y667813D03*
Y665845D03*
Y663876D03*
Y661908D03*
Y691436D03*
Y689467D03*
Y687499D03*
Y685530D03*
Y683562D03*
Y681593D03*
Y679624D03*
Y677656D03*
Y701278D03*
Y699310D03*
Y697341D03*
Y695373D03*
Y693404D03*
X510928Y650034D03*
Y652002D03*
Y653971D03*
Y655939D03*
Y657908D03*
Y659876D03*
Y661845D03*
Y663813D03*
Y665782D03*
Y667750D03*
Y669719D03*
Y671688D03*
Y673656D03*
Y675624D03*
Y677593D03*
Y679562D03*
Y681530D03*
Y683499D03*
Y685467D03*
Y687436D03*
Y689404D03*
Y691373D03*
Y693341D03*
Y695310D03*
Y697278D03*
X571952Y659876D03*
Y657908D03*
Y655939D03*
Y653971D03*
Y652002D03*
Y650034D03*
Y675624D03*
Y673656D03*
Y671688D03*
Y669719D03*
Y667750D03*
Y665782D03*
Y663813D03*
Y661845D03*
Y691373D03*
Y689404D03*
Y687436D03*
Y685467D03*
Y683499D03*
Y681530D03*
Y679562D03*
Y677593D03*
Y697278D03*
Y695310D03*
Y693341D03*
G54D152*
X509464Y452420D03*
Y453995D03*
Y455569D03*
Y457144D03*
Y458719D03*
Y460294D03*
Y461869D03*
Y463443D03*
Y465018D03*
Y466593D03*
Y468168D03*
Y469743D03*
Y471317D03*
Y472892D03*
X537416Y453995D03*
Y452420D03*
Y469743D03*
Y468168D03*
Y466593D03*
Y465018D03*
Y463443D03*
Y461869D03*
Y460294D03*
Y458719D03*
Y457144D03*
Y455569D03*
Y472892D03*
Y471317D03*
G54D161*
X553895Y239205D03*
Y240780D03*
Y242354D03*
Y243929D03*
Y245504D03*
Y247079D03*
Y248654D03*
Y250228D03*
Y251803D03*
Y253378D03*
Y254953D03*
Y256528D03*
Y258102D03*
Y259677D03*
Y261252D03*
Y262827D03*
Y264402D03*
Y265976D03*
Y267551D03*
X588865Y250228D03*
Y248654D03*
Y247079D03*
Y245504D03*
Y243929D03*
Y242354D03*
Y240780D03*
Y239205D03*
Y265976D03*
Y264402D03*
Y262827D03*
Y261252D03*
Y259677D03*
Y258102D03*
Y256528D03*
Y254953D03*
Y253378D03*
Y251803D03*
Y267551D03*
G54D134*
X413175Y525582D03*
Y527157D03*
Y528732D03*
Y530307D03*
Y531881D03*
Y533456D03*
Y535031D03*
Y536606D03*
X433057Y533456D03*
Y531881D03*
Y530307D03*
Y528732D03*
Y527157D03*
Y525582D03*
Y536606D03*
Y535031D03*
G54D14*
X10859Y109561D03*
X73740Y20708D03*
X703661D03*
G54D50*
X76880Y143269D03*
X739968Y29361D03*
G54D107*
X226331Y13885D03*
Y39081D03*
X245147Y13885D03*
Y39081D03*
G54D170*
X605796Y189845D03*
Y204845D03*
X611702Y185690D03*
Y178997D03*
Y200690D03*
Y193997D03*
G54D143*
X436202Y492873D03*
G54D60*
X102362Y247244D03*
Y349606D03*
X354331Y247244D03*
Y349606D03*
G54D126*
X385118Y691156D03*
Y696156D03*
Y701156D03*
Y706156D03*
X405918Y691156D03*
Y706156D03*
Y701156D03*
Y696156D03*
X493954Y250584D03*
Y255584D03*
Y260584D03*
Y265584D03*
X522588Y250584D03*
Y265584D03*
Y260584D03*
Y255584D03*
X559199Y601204D03*
Y606204D03*
Y611204D03*
Y616204D03*
X579999Y611204D03*
Y606204D03*
Y601204D03*
Y616204D03*
X613640Y339818D03*
Y344818D03*
Y349818D03*
Y354818D03*
X620131Y645072D03*
Y650072D03*
Y655072D03*
Y660072D03*
X634440Y344818D03*
Y339818D03*
Y354818D03*
Y349818D03*
X640931Y660072D03*
Y655072D03*
Y650072D03*
Y645072D03*
G54D180*
X688977Y105315D03*
Y719488D03*
G54D108*
X254383Y392464D03*
X251824D03*
X249265D03*
X246706D03*
X268052Y440162D03*
X270611D03*
X273170D03*
X275729D03*
X321404Y386129D03*
X318845D03*
X326522D03*
X323963D03*
G54D171*
X609300Y534523D03*
X618946D03*
X609300Y542003D03*
Y538263D03*
X618946Y542003D03*
X682880Y547065D03*
Y539585D03*
X692526D03*
Y543325D03*
Y547065D03*
G54D33*
X51395Y500840D03*
X65440Y164548D03*
X59640D03*
X66055Y223944D03*
X60255D03*
X57195Y500840D03*
X85829Y535202D03*
X79182Y583713D03*
X73382D03*
X91629Y535202D03*
X91717Y587077D03*
X97517D03*
X103080Y535202D03*
X108880D03*
X130102Y738065D03*
X124302D03*
X145375Y305640D03*
X139575D03*
X165512Y50968D03*
X159712D03*
X208209Y476153D03*
X214009D03*
X220428Y583822D03*
X226228D03*
X238952Y583627D03*
X233152D03*
X238852Y589327D03*
X233052D03*
X256606Y387964D03*
X250806D03*
X265696Y446936D03*
X271496D03*
X275509Y668795D03*
X269709D03*
X324696Y363647D03*
X330496D03*
X324696Y369147D03*
X330496D03*
X324732Y374642D03*
X330532D03*
X332439Y380334D03*
X326639D03*
X342520Y303938D03*
X348320D03*
X340926Y317597D03*
X346726D03*
X409149Y71906D03*
X414949D03*
X403124Y558626D03*
X409024D03*
X451563Y101680D03*
X445663D03*
X448182Y262291D03*
X447975Y604522D03*
X457394Y187205D03*
X463194D03*
X453982Y262291D03*
X453775Y604522D03*
X473153Y617880D03*
X467353D03*
X495888Y655413D03*
X501688D03*
X535772Y253862D03*
X541572D03*
X714559Y563230D03*
X720359D03*
X725495Y593262D03*
X731295D03*
X757507Y564565D03*
X763307D03*
X757614Y570468D03*
X763414D03*
G54D117*
X306809Y390104D03*
Y381443D03*
X299919D03*
Y390104D03*
G54D153*
X510779Y534746D03*
X509205D03*
X507630D03*
X506055D03*
X504480D03*
X502905D03*
X501331D03*
Y595770D03*
X502905D03*
X504480D03*
X506055D03*
X507630D03*
X509205D03*
X510779D03*
X526527Y534746D03*
X524953D03*
X523378D03*
X521803D03*
X520228D03*
X518653D03*
X517079D03*
X515504D03*
X513929D03*
X512354D03*
Y595770D03*
X513929D03*
X515504D03*
X517079D03*
X518653D03*
X520228D03*
X521803D03*
X523378D03*
X524953D03*
X526527D03*
X542275Y534746D03*
X540701D03*
X539126D03*
X537551D03*
X535976D03*
X534401D03*
X532827D03*
X531252D03*
X529677D03*
X528102D03*
Y595770D03*
X529677D03*
X531252D03*
X532827D03*
X534401D03*
X535976D03*
X537551D03*
X539126D03*
X540701D03*
X542275D03*
X550149Y534746D03*
X548575D03*
X547000D03*
X545425D03*
X543850D03*
Y595770D03*
X545425D03*
X547000D03*
X548575D03*
X550149D03*
G54D162*
X557454Y624762D03*
X548793D03*
Y631652D03*
X557454D03*
G54D24*
X36024Y187233D03*
Y181225D03*
Y205257D03*
Y199249D03*
Y193241D03*
Y217272D03*
Y211264D03*
X41930Y178221D03*
Y202253D03*
Y196245D03*
Y190237D03*
Y220276D03*
Y214268D03*
Y208260D03*
G54D135*
X434102Y232640D03*
Y311875D03*
X583913Y69167D03*
X608571D03*
G54D15*
X20859Y109561D03*
X83740Y20708D03*
X78740Y30708D03*
X507489Y360278D03*
X713661Y20708D03*
X708661Y30708D03*
G54D51*
X86880Y143269D03*
X749968Y29361D03*
G54D144*
X454263Y87816D03*
G54D42*
X67640Y493618D03*
G54D163*
X571380Y253378D03*
G54D25*
X47220Y28062D03*
X43480D03*
X39740D03*
Y37708D03*
X47220D03*
X424700Y661479D03*
X432180D03*
Y651833D03*
X428440D03*
X424700D03*
G54D52*
X85951Y383568D03*
Y404368D03*
X100951Y383568D03*
X95951D03*
X90951D03*
Y404368D03*
X95951D03*
X100951D03*
X224269Y602633D03*
Y623433D03*
X239269Y602633D03*
X234269D03*
X229269D03*
Y623433D03*
X234269D03*
X239269D03*
X352079Y381319D03*
X347079D03*
Y409953D03*
X352079D03*
X362079Y381319D03*
X357079D03*
Y409953D03*
X362079D03*
G54D145*
X451840Y639199D03*
Y641758D03*
Y644317D03*
Y646876D03*
Y649436D03*
Y651995D03*
Y654554D03*
Y657113D03*
Y661699D03*
Y664258D03*
Y666817D03*
Y669376D03*
Y671936D03*
Y674495D03*
Y677054D03*
Y679613D03*
X474840Y644317D03*
Y641758D03*
Y639199D03*
Y657113D03*
Y654554D03*
Y651995D03*
Y649436D03*
Y646876D03*
Y674495D03*
Y671936D03*
Y669376D03*
Y666817D03*
Y664258D03*
Y661699D03*
Y679613D03*
Y677054D03*
X600118Y115098D03*
Y117657D03*
Y120216D03*
Y122775D03*
Y125334D03*
Y127893D03*
Y130452D03*
Y133012D03*
Y135571D03*
Y138130D03*
Y140689D03*
Y143248D03*
Y145807D03*
Y148366D03*
X623118Y122775D03*
Y120216D03*
Y117657D03*
Y115098D03*
Y138130D03*
Y135571D03*
Y133012D03*
Y130452D03*
Y127893D03*
Y125334D03*
Y148366D03*
Y145807D03*
Y143248D03*
Y140689D03*
X627463Y675600D03*
Y678159D03*
Y680718D03*
Y683277D03*
Y685836D03*
Y688395D03*
Y690954D03*
Y693514D03*
Y696073D03*
Y698632D03*
Y701191D03*
Y703750D03*
Y706309D03*
Y708868D03*
X650463Y675600D03*
Y690954D03*
Y688395D03*
Y685836D03*
Y683277D03*
Y680718D03*
Y678159D03*
Y706309D03*
Y703750D03*
Y701191D03*
Y698632D03*
Y696073D03*
Y693514D03*
Y708868D03*
G54D34*
X55256Y625732D03*
Y637332D03*
X116383Y576727D03*
Y588327D03*
X164948Y8617D03*
Y20217D03*
X181582Y11345D03*
Y22945D03*
X190011Y11535D03*
Y23135D03*
X199840Y11316D03*
Y22916D03*
X456988Y479623D03*
X465255Y479621D03*
X456988Y491223D03*
X465255Y491221D03*
X462344Y499662D03*
Y511262D03*
X718335Y581651D03*
Y593251D03*
X747439Y641672D03*
Y653272D03*
G54D118*
X305097Y647144D03*
X303129D03*
X301160D03*
X299192D03*
X297223D03*
X295255D03*
X293286D03*
X291318D03*
Y708168D03*
X293286D03*
X295255D03*
X297223D03*
X299192D03*
X301160D03*
X303129D03*
X305097D03*
X320846Y647144D03*
X318877D03*
X316908D03*
X314940D03*
X312972D03*
X311003D03*
X309034D03*
X307066D03*
Y708168D03*
X309034D03*
X311003D03*
X312972D03*
X314940D03*
X316908D03*
X318877D03*
X320846D03*
X336594Y647144D03*
X334625D03*
X332657D03*
X330688D03*
X328720D03*
X326751D03*
X324783D03*
X322814D03*
Y708168D03*
X324783D03*
X326751D03*
X328720D03*
X330688D03*
X332657D03*
X334625D03*
X336594D03*
X338562Y647144D03*
Y708168D03*
X525692Y643144D03*
X523723D03*
X521755D03*
X519786D03*
X517818D03*
Y704168D03*
X519786D03*
X521755D03*
X523723D03*
X525692D03*
X541440Y643144D03*
X539472D03*
X537503D03*
X535534D03*
X533566D03*
X531597D03*
X529629D03*
X527660D03*
Y704168D03*
X529629D03*
X531597D03*
X533566D03*
X535534D03*
X537503D03*
X539472D03*
X541440D03*
X557188Y643144D03*
X555220D03*
X553251D03*
X551283D03*
X549314D03*
X547346D03*
X545377D03*
X543408D03*
Y704168D03*
X545377D03*
X547346D03*
X549314D03*
X551283D03*
X553251D03*
X555220D03*
X557188D03*
X565062Y643144D03*
X563094D03*
X561125D03*
X559157D03*
Y704168D03*
X561125D03*
X563094D03*
X565062D03*
G54D127*
X395227Y633135D03*
Y640615D03*
X403101Y636875D03*
X535735Y259622D03*
Y267102D03*
X543609Y263362D03*
G54D16*
X25439Y303260D03*
Y356804D03*
G54D181*
X683806Y158536D03*
Y168182D03*
X683844Y237342D03*
Y246988D03*
X691286Y158536D03*
X687546D03*
Y168182D03*
X691286D03*
X691324Y237342D03*
X687584D03*
Y246988D03*
X691324D03*
G54D43*
X64089Y489779D03*
Y492338D03*
Y494898D03*
Y497457D03*
X80553D03*
G54D109*
X250545Y399984D03*
X322684Y393649D03*
G54D172*
X652139Y382018D03*
X650564D03*
X648989D03*
X647414D03*
Y412752D03*
X648989D03*
X650564D03*
X652139D03*
X667887Y382018D03*
X666312D03*
X664737D03*
X663162D03*
X661588D03*
X660013D03*
X658438D03*
X656863D03*
X655288D03*
X653714D03*
Y412752D03*
X655288D03*
X656863D03*
X658438D03*
X660013D03*
X661588D03*
X663162D03*
X664737D03*
X666312D03*
X667887D03*
X669462Y382018D03*
Y412752D03*
G54D70*
X143779Y37407D03*
Y38982D03*
Y40557D03*
Y42132D03*
Y43707D03*
X156085D03*
Y42132D03*
Y40557D03*
Y38982D03*
Y37407D03*
X413105Y524007D03*
Y538181D03*
X433127Y524007D03*
Y538181D03*
G54D136*
X428747Y455592D03*
Y477403D03*
G54D190*
X749907Y573179D03*
G54D61*
X97150Y553052D03*
G54D154*
X514780Y28803D03*
X524780D03*
X514780Y38803D03*
X524780D03*
X534780Y28803D03*
X544780D03*
X534780Y38803D03*
X544780D03*
X554780Y28803D03*
X577371D03*
X587371D03*
X577371Y38803D03*
X587371D03*
X597371Y28803D03*
X607371D03*
X597371Y38803D03*
X607371D03*
X617371Y28803D03*
X639963D03*
Y38803D03*
X649963Y28803D03*
Y38803D03*
X659963Y28803D03*
X669963D03*
X659963Y38803D03*
X669963D03*
X679963Y28803D03*
G54D191*
G01X5906Y278740D02*
X25591D01*
G02X31496Y272835I0J-5905D01*
G01Y127165D01*
G02X25591Y121260I-5905J0D01*
G01X5906D01*
G03X0Y115354I0J-5906D01*
G01Y7874D01*
G03X7874Y0I7874J0D01*
G01X779528D01*
G03X787402Y7874I0J7874D01*
G01Y120669D01*
G03X781496Y126575I-5906J0D01*
G01X780315D01*
G02X774409Y132480I0J5906D01*
G01Y286024D01*
G02X780315Y291929I5906J-1D01*
G01X781496D01*
G03X787402Y297835I0J5906D01*
G01Y664173D01*
G03X779528Y672047I-7874J0D01*
G01X746693D01*
G02X738819Y679921I0J7874D01*
G01Y819708D01*
X738695Y819832D01*
X736866Y821652D01*
G01X5906Y278740D02*
G02X0Y284646I0J5906D01*
G01Y664173D01*
G02X7874Y672047I7874J0D01*
G01X40787D01*
G03X48661Y679921I0J7874D01*
G01Y819674D01*
X49201Y820214D01*
X50646Y821652D01*
G01X327026D02*
X50646D01*
G01X89851Y96614D02*
G03X107000I8574J-10787D01*
G01X89851Y710787D02*
G03X107000I8574J-10787D01*
G01X105512Y105512D02*
G03X91339I-7086J0D01*
G01X89852Y96614D02*
G03X91339Y99696I-2450J3082D01*
G01Y105512D02*
Y99696D01*
G01X105512Y719685D02*
G03X91339I-7086J0D01*
G01X89852Y710787D02*
G03X91339Y713869I-2450J3082D01*
G01Y719685D02*
Y713869D01*
G01X105512Y99696D02*
G03X107000Y96614I3937J1D01*
G01X105512Y99696D02*
Y105512D01*
G01Y713869D02*
G03X107000Y710787I3937J1D01*
G01X105512Y713869D02*
Y719685D01*
G01X327026Y821652D02*
X328915Y819773D01*
X328976Y819712D01*
Y792323D01*
G03X336457I3740J0D01*
G01Y819673D01*
X336476Y819692D01*
X338446Y821652D01*
G01X378606D02*
X338446D01*
G01X378606D02*
X380551Y819707D01*
Y741142D01*
G03X406929I13189J0D01*
G01Y819675D01*
X406946Y819692D01*
X408916Y821652D01*
G01X685296D02*
X408916D01*
G01X680097Y96167D02*
G03X697856I8880J-10537D01*
G01X680097Y96166D02*
G03X681497Y99177I-2537J3011D01*
G01X696457Y105315D02*
G03X681497I-7480J0D01*
G01D02*
Y99177D01*
G01X680097Y710340D02*
G03X697856I8880J-10537D01*
G01X696457Y719488D02*
G03X681497I-7480J0D01*
G01X680097Y710340D02*
G03X681497Y713350I-2537J3011D01*
G01Y719488D02*
Y713350D01*
G01X696457Y99177D02*
G03X697857Y96166I3937J0D01*
G01X696457Y99177D02*
Y105315D01*
G01Y713350D02*
G03X697857Y710340I3937J1D01*
G01X696457Y713350D02*
Y719488D01*
G01X696716Y821652D02*
X694746Y819692D01*
X694724Y819670D01*
Y792323D01*
G02X687244I-3740J0D01*
G01Y819710D01*
X686388Y820566D01*
X685296Y821652D01*
G01X736866D02*
X696716D01*
G54D119*
X332490Y328505D03*
Y338347D03*
X695230Y201790D03*
Y190373D03*
X748713Y125542D03*
Y114125D03*
G54D155*
X525802Y448680D03*
X524227D03*
X522653D03*
X521078D03*
X519503D03*
X517928D03*
X516353D03*
X514779D03*
X513204D03*
Y476632D03*
X514779D03*
X516353D03*
X517928D03*
X519503D03*
X521078D03*
X522653D03*
X524227D03*
X525802D03*
X533676Y448680D03*
X532101D03*
X530527D03*
X528952D03*
X527377D03*
Y476632D03*
X528952D03*
X530527D03*
X532101D03*
X533676D03*
G54D146*
X481102Y34528D03*
G54D137*
X428747Y458694D03*
Y474305D03*
G54D173*
X645840Y381668D03*
Y413102D03*
X671036Y381668D03*
Y413102D03*
G54D80*
X162668Y592020D03*
X160699D03*
Y627846D03*
X162668D03*
X178416Y592020D03*
X176447D03*
X174479D03*
X172510D03*
X170542D03*
X168573D03*
X166605D03*
X164636D03*
Y627846D03*
X166605D03*
X168573D03*
X170542D03*
X172510D03*
X174479D03*
X176447D03*
X178416D03*
X190227Y592020D03*
X188258D03*
X186290D03*
X184321D03*
X182353D03*
X180384D03*
Y627846D03*
X182353D03*
X184321D03*
X186290D03*
X188258D03*
X190227D03*
X621142Y584832D03*
X619173D03*
Y620658D03*
X621142D03*
X636890Y584832D03*
X634921D03*
X632953D03*
X630984D03*
X629016D03*
X627047D03*
X625079D03*
X623110D03*
Y620658D03*
X625079D03*
X627047D03*
X629016D03*
X630984D03*
X632953D03*
X634921D03*
X636890D03*
X648701Y584832D03*
X646732D03*
X644764D03*
X642795D03*
X640827D03*
X638858D03*
Y620658D03*
X640827D03*
X642795D03*
X644764D03*
X646732D03*
X648701D03*
G54D128*
X399337Y716398D03*
Y713839D03*
Y711280D03*
X391857D03*
Y713839D03*
Y716398D03*
G54D71*
X148357Y34404D03*
X146782D03*
Y46710D03*
X148357D03*
X153082Y34404D03*
X151507D03*
X149932D03*
X153082Y46710D03*
X151507D03*
X149932D03*
X416029Y521083D03*
Y541105D03*
X430203Y521083D03*
Y541105D03*
G54D44*
X63237Y512883D03*
G54D53*
X77499Y457491D03*
Y480521D03*
G54D164*
X590999Y69167D03*
Y77041D03*
Y84915D03*
X615657Y69167D03*
Y77041D03*
Y84915D03*
G54D17*
X23628Y321764D03*
Y338300D03*
X45282Y321764D03*
G54D182*
X677206Y469943D03*
X681143D03*
X677206Y466006D03*
X681143D03*
X677206Y462069D03*
X681143D03*
X677206Y458132D03*
X681143D03*
X677206Y485692D03*
X681143D03*
X677206Y481755D03*
X681143D03*
X677206Y477817D03*
X681143D03*
X677206Y473881D03*
X681143D03*
X677206Y493566D03*
X681143D03*
X677206Y489629D03*
X681143D03*
X685080Y469943D03*
X689017D03*
X692955D03*
X696891D03*
X685080Y466006D03*
X689017D03*
X692955D03*
X696891D03*
X685080Y462069D03*
X689017D03*
X692955D03*
X696891D03*
X685080Y458132D03*
X689017D03*
X692955D03*
X696891D03*
X685080Y485692D03*
X689017D03*
X692955D03*
X696891D03*
X685080Y481755D03*
X689017D03*
X692955D03*
X696891D03*
X685080Y477817D03*
X689017D03*
X692955D03*
X696891D03*
X685080Y473881D03*
X689017D03*
X692955D03*
X696891D03*
X685080Y493566D03*
X689017D03*
X692955D03*
X696891D03*
X685080Y489629D03*
X689017D03*
X692955D03*
X696891D03*
X700829Y469943D03*
X704766D03*
X708703D03*
X712640D03*
X700829Y466006D03*
X704766D03*
X708703D03*
X712640D03*
X700829Y462069D03*
X704766D03*
X708703D03*
X712640D03*
X700829Y458132D03*
X704766D03*
X708703D03*
X712640D03*
X700829Y485692D03*
X704766D03*
X708703D03*
X712640D03*
X700829Y481755D03*
X704766D03*
X708703D03*
X712640D03*
X700829Y477817D03*
X704766D03*
X708703D03*
X712640D03*
X700829Y473881D03*
X704766D03*
X708703D03*
X712640D03*
X700829Y493566D03*
X704766D03*
X708703D03*
X712640D03*
X700829Y489629D03*
X704766D03*
X708703D03*
X712640D03*
G54D62*
X120635Y499230D03*
X330425Y556306D03*
X375349Y530269D03*
G54D26*
X40749Y150808D03*
Y249194D03*
G54D35*
X51240Y807872D03*
X59114D03*
X63051D03*
X66988D03*
X70925D03*
X74862D03*
X78799D03*
X82736D03*
X86673D03*
X90610D03*
X94547D03*
X98484D03*
X102421D03*
X106358D03*
X110295D03*
X114232D03*
X118169D03*
X122106D03*
X126043D03*
X129980D03*
X133917D03*
X137854D03*
X141791D03*
X145728D03*
X149665D03*
X153602D03*
X157539D03*
X161476D03*
X165413D03*
X169350D03*
X173287D03*
X177224D03*
X181161D03*
X189035D03*
X192972D03*
X196909D03*
X200846D03*
X204783D03*
X208720D03*
X212658D03*
X216594D03*
X220532D03*
X224469D03*
X228406D03*
X232343D03*
X236280D03*
X240217D03*
X244154D03*
X248091D03*
X255965D03*
X259902D03*
X263839D03*
X267776D03*
X271713D03*
X275650D03*
X279587D03*
X283524D03*
X287461D03*
X291398D03*
X295335D03*
X299272D03*
X303209D03*
X311083D03*
X315020D03*
X318957D03*
X322894D03*
X326831D03*
X338642D03*
X342579D03*
X346516D03*
X350453D03*
X354390D03*
X358327D03*
X362264D03*
X366201D03*
X370138D03*
X374075D03*
X378012D03*
X409510D03*
X417384D03*
X421321D03*
X425258D03*
X429195D03*
X433132D03*
X437069D03*
X441006D03*
X444943D03*
X448880D03*
X452817D03*
X456754D03*
X460691D03*
X464628D03*
X468565D03*
X472502D03*
X476439D03*
X480376D03*
X484313D03*
X488250D03*
X492187D03*
X496124D03*
X500061D03*
X503998D03*
X507935D03*
X511872D03*
X515809D03*
X519746D03*
X523683D03*
X527620D03*
X531557D03*
X535494D03*
X539431D03*
X547305D03*
X551242D03*
X555179D03*
X559116D03*
X563053D03*
X566990D03*
X570928D03*
X574864D03*
X578802D03*
X582739D03*
X586676D03*
X590613D03*
X594550D03*
X598487D03*
X602424D03*
X606361D03*
X614235D03*
X618172D03*
X622109D03*
X626046D03*
X629983D03*
X633920D03*
X637857D03*
X641794D03*
X645731D03*
X649668D03*
X653605D03*
X657542D03*
X661479D03*
X669353D03*
X673290D03*
X677227D03*
X681164D03*
X685101D03*
X696912D03*
X700849D03*
X704786D03*
X708723D03*
X712660D03*
X716597D03*
X720534D03*
X724471D03*
X728408D03*
X732345D03*
X736282D03*
G54D192*
G01X38493Y-241864D02*
Y-246864D01*
G01X37036Y-241864D02*
X39950D01*
G01X44860Y-246864D02*
X42326D01*
Y-241864D01*
X44860D01*
G01X43846Y-244281D02*
X42326D01*
G01X47426Y-241864D02*
Y-246864D01*
X49960D01*
G01X53793Y-247031D02*
X53666Y-246947D01*
Y-246781D01*
X53793Y-246697D01*
X53920Y-246781D01*
Y-246947D01*
X53793Y-247031D01*
G01Y-244781D02*
X53666Y-244697D01*
Y-244531D01*
X53793Y-244447D01*
X53920Y-244531D01*
Y-244697D01*
X53793Y-244781D01*
G01X58576Y-248531D02*
X57943Y-247697D01*
X57626Y-246864D01*
Y-243531D01*
X57943Y-242697D01*
X58576Y-241864D01*
G01X63993D02*
X63486Y-242031D01*
X63106Y-242447D01*
X62853Y-242947D01*
X62663Y-243614D01*
X62600Y-244364D01*
X62663Y-245114D01*
X62853Y-245781D01*
X63106Y-246281D01*
X63486Y-246697D01*
X63993Y-246864D01*
X64500Y-246697D01*
X64880Y-246281D01*
X65133Y-245781D01*
X65323Y-245114D01*
X65386Y-244364D01*
X65323Y-243614D01*
X65133Y-242947D01*
X64880Y-242447D01*
X64500Y-242031D01*
X63993Y-241864D01*
G01X67700Y-245864D02*
X68080Y-246447D01*
X68586Y-246781D01*
X69156Y-246864D01*
X69663Y-246781D01*
X70170Y-246364D01*
X70486Y-245864D01*
X70550Y-245364D01*
X70423Y-244781D01*
X69980Y-244364D01*
X69536Y-244197D01*
X68966D01*
G01X69536D02*
X69916Y-243947D01*
X70233Y-243531D01*
X70360Y-243031D01*
X70233Y-242531D01*
X69916Y-242114D01*
X69346Y-241864D01*
X68776Y-241947D01*
X68206Y-242281D01*
G01X74510Y-248531D02*
X75143Y-247697D01*
X75460Y-246864D01*
Y-243531D01*
X75143Y-242697D01*
X74510Y-241864D01*
G01X77900Y-245864D02*
X78280Y-246447D01*
X78786Y-246781D01*
X79356Y-246864D01*
X79863Y-246781D01*
X80370Y-246364D01*
X80686Y-245864D01*
X80750Y-245364D01*
X80623Y-244781D01*
X80180Y-244364D01*
X79736Y-244197D01*
X79166D01*
G01X79736D02*
X80116Y-243947D01*
X80433Y-243531D01*
X80560Y-243031D01*
X80433Y-242531D01*
X80116Y-242114D01*
X79546Y-241864D01*
X78976Y-241947D01*
X78406Y-242281D01*
G01X83190Y-242697D02*
X83570Y-242197D01*
X84013Y-241947D01*
X84520Y-241864D01*
X85153Y-242031D01*
X85596Y-242447D01*
X85723Y-242947D01*
X85660Y-243447D01*
X85406Y-243864D01*
X84140Y-244697D01*
X83570Y-245281D01*
X83190Y-246114D01*
X83063Y-246864D01*
X85723D01*
G01X89366D02*
X89493Y-245781D01*
X89683Y-244864D01*
X89936Y-244031D01*
X90253Y-243114D01*
X90760Y-241864D01*
X88226D01*
G01X93770Y-245197D02*
X95416D01*
G01X98490Y-242697D02*
X98870Y-242197D01*
X99313Y-241947D01*
X99820Y-241864D01*
X100453Y-242031D01*
X100896Y-242447D01*
X101023Y-242947D01*
X100960Y-243447D01*
X100706Y-243864D01*
X99440Y-244697D01*
X98870Y-245281D01*
X98490Y-246114D01*
X98363Y-246864D01*
X101023D01*
G01X103400Y-245864D02*
X103780Y-246447D01*
X104286Y-246781D01*
X104856Y-246864D01*
X105363Y-246781D01*
X105870Y-246364D01*
X106186Y-245864D01*
X106250Y-245364D01*
X106123Y-244781D01*
X105680Y-244364D01*
X105236Y-244197D01*
X104666D01*
G01X105236D02*
X105616Y-243947D01*
X105933Y-243531D01*
X106060Y-243031D01*
X105933Y-242531D01*
X105616Y-242114D01*
X105046Y-241864D01*
X104476Y-241947D01*
X103906Y-242281D01*
G01X110653Y-246864D02*
Y-241864D01*
X108310Y-245447D01*
X111476D01*
G01X113600Y-246114D02*
X113980Y-246531D01*
X114423Y-246781D01*
X114993Y-246864D01*
X115563Y-246697D01*
X116006Y-246364D01*
X116323Y-245781D01*
X116386Y-245114D01*
X116260Y-244447D01*
X115943Y-244031D01*
X115500Y-243697D01*
X115056Y-243614D01*
X114613Y-243697D01*
X114043Y-244031D01*
X114233Y-241864D01*
X115943D01*
G01X123990Y-246864D02*
Y-241864D01*
X126396D01*
G01X125510Y-244281D02*
X123990D01*
G01X128710Y-246864D02*
X130293Y-241864D01*
X131876Y-246864D01*
G01X131306Y-245114D02*
X129280D01*
G01X134063Y-246864D02*
X136723Y-241864D01*
G01X134063D02*
X136723Y-246864D01*
G01X140493Y-247031D02*
X140366Y-246947D01*
Y-246781D01*
X140493Y-246697D01*
X140620Y-246781D01*
Y-246947D01*
X140493Y-247031D01*
G01Y-244781D02*
X140366Y-244697D01*
Y-244531D01*
X140493Y-244447D01*
X140620Y-244531D01*
Y-244697D01*
X140493Y-244781D01*
G01X145276Y-248531D02*
X144643Y-247697D01*
X144326Y-246864D01*
Y-243531D01*
X144643Y-242697D01*
X145276Y-241864D01*
G01X150693D02*
X150186Y-242031D01*
X149806Y-242447D01*
X149553Y-242947D01*
X149363Y-243614D01*
X149300Y-244364D01*
X149363Y-245114D01*
X149553Y-245781D01*
X149806Y-246281D01*
X150186Y-246697D01*
X150693Y-246864D01*
X151200Y-246697D01*
X151580Y-246281D01*
X151833Y-245781D01*
X152023Y-245114D01*
X152086Y-244364D01*
X152023Y-243614D01*
X151833Y-242947D01*
X151580Y-242447D01*
X151200Y-242031D01*
X150693Y-241864D01*
G01X154400Y-245864D02*
X154780Y-246447D01*
X155286Y-246781D01*
X155856Y-246864D01*
X156363Y-246781D01*
X156870Y-246364D01*
X157186Y-245864D01*
X157250Y-245364D01*
X157123Y-244781D01*
X156680Y-244364D01*
X156236Y-244197D01*
X155666D01*
G01X156236D02*
X156616Y-243947D01*
X156933Y-243531D01*
X157060Y-243031D01*
X156933Y-242531D01*
X156616Y-242114D01*
X156046Y-241864D01*
X155476Y-241947D01*
X154906Y-242281D01*
G01X161210Y-248531D02*
X161843Y-247697D01*
X162160Y-246864D01*
Y-243531D01*
X161843Y-242697D01*
X161210Y-241864D01*
G01X164600Y-245864D02*
X164980Y-246447D01*
X165486Y-246781D01*
X166056Y-246864D01*
X166563Y-246781D01*
X167070Y-246364D01*
X167386Y-245864D01*
X167450Y-245364D01*
X167323Y-244781D01*
X166880Y-244364D01*
X166436Y-244197D01*
X165866D01*
G01X166436D02*
X166816Y-243947D01*
X167133Y-243531D01*
X167260Y-243031D01*
X167133Y-242531D01*
X166816Y-242114D01*
X166246Y-241864D01*
X165676Y-241947D01*
X165106Y-242281D01*
G01X170016Y-246281D02*
X170460Y-246697D01*
X170966Y-246864D01*
X171473Y-246697D01*
X171916Y-246197D01*
X172233Y-245447D01*
X172360Y-244697D01*
Y-243781D01*
X172233Y-243031D01*
X171916Y-242364D01*
X171536Y-242031D01*
X171093Y-241864D01*
X170586Y-242031D01*
X170206Y-242364D01*
X169953Y-242864D01*
X169826Y-243531D01*
X169953Y-244114D01*
X170270Y-244697D01*
X170650Y-245031D01*
X171093Y-245114D01*
X171600Y-244947D01*
X171980Y-244531D01*
X172360Y-243781D01*
G01X176066Y-246864D02*
X176193Y-245781D01*
X176383Y-244864D01*
X176636Y-244031D01*
X176953Y-243114D01*
X177460Y-241864D01*
X174926D01*
G01X180470Y-245197D02*
X182116D01*
G01X185000Y-245864D02*
X185380Y-246447D01*
X185886Y-246781D01*
X186456Y-246864D01*
X186963Y-246781D01*
X187470Y-246364D01*
X187786Y-245864D01*
X187850Y-245364D01*
X187723Y-244781D01*
X187280Y-244364D01*
X186836Y-244197D01*
X186266D01*
G01X186836D02*
X187216Y-243947D01*
X187533Y-243531D01*
X187660Y-243031D01*
X187533Y-242531D01*
X187216Y-242114D01*
X186646Y-241864D01*
X186076Y-241947D01*
X185506Y-242281D01*
G01X190290Y-244781D02*
X190733Y-244197D01*
X191113Y-243864D01*
X191620Y-243697D01*
X192063Y-243864D01*
X192380Y-244197D01*
X192633Y-244697D01*
X192696Y-245281D01*
X192633Y-245781D01*
X192380Y-246281D01*
X192000Y-246697D01*
X191556Y-246864D01*
X191050Y-246697D01*
X190606Y-246197D01*
X190353Y-245447D01*
X190290Y-244614D01*
X190416Y-243531D01*
X190606Y-242947D01*
X190923Y-242364D01*
X191366Y-241947D01*
X191810Y-241864D01*
X192253Y-242031D01*
X192570Y-242447D01*
G01X196593Y-246864D02*
Y-241864D01*
X195833Y-242864D01*
G01Y-246864D02*
X197353D01*
G01X202453D02*
Y-241864D01*
X200110Y-245447D01*
X203276D01*
G01X26493Y-176864D02*
Y-251864D01*
X526493D01*
Y-176864D01*
X26493D01*
G01X221493D02*
Y-251864D01*
G01Y-226864D02*
X324493D01*
Y-201864D01*
G01X221493D02*
X324493D01*
G01X332000Y-236864D02*
Y-231864D01*
X333266D01*
X333773Y-232114D01*
X334153Y-232447D01*
X334470Y-232947D01*
X334723Y-233531D01*
X334786Y-234364D01*
X334723Y-235197D01*
X334470Y-235781D01*
X334153Y-236281D01*
X333773Y-236614D01*
X333266Y-236864D01*
X332000D01*
G01X336910D02*
X338493Y-231864D01*
X340076Y-236864D01*
G01X339506Y-235114D02*
X337480D01*
G01X343593Y-231864D02*
Y-236864D01*
G01X342136Y-231864D02*
X345050D01*
G01X349960Y-236864D02*
X347426D01*
Y-231864D01*
X349960D01*
G01X348946Y-234281D02*
X347426D01*
G01X353793Y-237031D02*
X353666Y-236947D01*
Y-236781D01*
X353793Y-236697D01*
X353920Y-236781D01*
Y-236947D01*
X353793Y-237031D01*
G01Y-234781D02*
X353666Y-234697D01*
Y-234531D01*
X353793Y-234447D01*
X353920Y-234531D01*
Y-234697D01*
X353793Y-234781D01*
G01X326493Y-176864D02*
Y-251864D01*
G01X324493Y-176864D02*
Y-251864D01*
G01X326493Y-226864D02*
X526493D01*
G01X332126Y-211864D02*
Y-206864D01*
X333646D01*
X334153Y-207114D01*
X334533Y-207697D01*
X334660Y-208364D01*
X334533Y-209031D01*
X334216Y-209531D01*
X333646Y-209781D01*
X332126D01*
G01X337353Y-212031D02*
X339633Y-206864D01*
G01X342136Y-211864D02*
Y-206864D01*
X345050Y-211864D01*
Y-206864D01*
G01X348693Y-212031D02*
X348566Y-211947D01*
Y-211781D01*
X348693Y-211697D01*
X348820Y-211781D01*
Y-211947D01*
X348693Y-212031D01*
G01Y-209781D02*
X348566Y-209697D01*
Y-209531D01*
X348693Y-209447D01*
X348820Y-209531D01*
Y-209697D01*
X348693Y-209781D01*
G01X326493Y-201864D02*
X526493D01*
G01X332126Y-186864D02*
Y-181864D01*
X333646D01*
X334153Y-182114D01*
X334533Y-182697D01*
X334660Y-183364D01*
X334533Y-184031D01*
X334216Y-184531D01*
X333646Y-184781D01*
X332126D01*
G01X337226Y-186864D02*
Y-181864D01*
X338810D01*
X339316Y-182114D01*
X339633Y-182447D01*
X339760Y-183114D01*
X339633Y-183781D01*
X339253Y-184197D01*
X338810Y-184447D01*
X337226D01*
G01X338810D02*
X339760Y-186864D01*
G01X343593D02*
X343086Y-186781D01*
X342643Y-186447D01*
X342263Y-185947D01*
X342010Y-185364D01*
X341883Y-184697D01*
Y-184031D01*
X342010Y-183364D01*
X342263Y-182781D01*
X342643Y-182281D01*
X343086Y-181947D01*
X343593Y-181864D01*
X344100Y-181947D01*
X344543Y-182281D01*
X344923Y-182781D01*
X345176Y-183364D01*
X345303Y-184031D01*
Y-184697D01*
X345176Y-185364D01*
X344923Y-185947D01*
X344543Y-186447D01*
X344100Y-186781D01*
X343593Y-186864D01*
G01X347426Y-185864D02*
X347743Y-186364D01*
X348123Y-186697D01*
X348566Y-186864D01*
X349073Y-186697D01*
X349453Y-186364D01*
X349833Y-185864D01*
X349960Y-185197D01*
Y-181864D01*
G01X355060Y-186864D02*
X352526D01*
Y-181864D01*
X355060D01*
G01X354046Y-184281D02*
X352526D01*
G01X360286Y-182281D02*
X359906Y-182031D01*
X359463Y-181864D01*
X358956D01*
X358386Y-182114D01*
X357943Y-182531D01*
X357626Y-183031D01*
X357373Y-183864D01*
X357310Y-184614D01*
X357436Y-185364D01*
X357626Y-185864D01*
X358006Y-186364D01*
X358450Y-186697D01*
X358893Y-186864D01*
X359336D01*
X359780Y-186697D01*
X360160Y-186447D01*
X360476Y-186114D01*
G01X363993Y-181864D02*
Y-186864D01*
G01X362536Y-181864D02*
X365450D01*
G01X369093Y-187031D02*
X368966Y-186947D01*
Y-186781D01*
X369093Y-186697D01*
X369220Y-186781D01*
Y-186947D01*
X369093Y-187031D01*
G01Y-184781D02*
X368966Y-184697D01*
Y-184531D01*
X369093Y-184447D01*
X369220Y-184531D01*
Y-184697D01*
X369093Y-184781D01*
G01X447126Y-236864D02*
Y-231864D01*
X448710D01*
X449216Y-232114D01*
X449533Y-232447D01*
X449660Y-233114D01*
X449533Y-233781D01*
X449153Y-234197D01*
X448710Y-234447D01*
X447126D01*
G01X448710D02*
X449660Y-236864D01*
G01X454760D02*
X452226D01*
Y-231864D01*
X454760D01*
G01X453746Y-234281D02*
X452226D01*
G01X457010Y-231864D02*
X458593Y-236864D01*
X460176Y-231864D01*
G01X463693Y-237031D02*
X463566Y-236947D01*
Y-236781D01*
X463693Y-236697D01*
X463820Y-236781D01*
Y-236947D01*
X463693Y-237031D01*
G01Y-234781D02*
X463566Y-234697D01*
Y-234531D01*
X463693Y-234447D01*
X463820Y-234531D01*
Y-234697D01*
X463693Y-234781D01*
G01X441493Y-226864D02*
Y-251864D01*
G01X490493Y-226864D02*
Y-251864D01*
G01X-1043962Y-705877D02*
Y2342823D01*
X2300638D01*
Y-705877D01*
X-1043962D01*
G01X37198Y-238524D02*
X37825Y-239049D01*
X38530Y-239364D01*
X39156D01*
X39783Y-239049D01*
X40253Y-238524D01*
X40488Y-237789D01*
X40331Y-237054D01*
X39940Y-236424D01*
X39235Y-236004D01*
X38295Y-235794D01*
X37746Y-235374D01*
X37511Y-234639D01*
X37668Y-233904D01*
X38060Y-233379D01*
X38608Y-233064D01*
X39156D01*
X39705Y-233274D01*
X40175Y-233799D01*
G01X43498Y-239364D02*
Y-233064D01*
G01X46788D02*
Y-239364D01*
G01Y-236214D02*
X43498D01*
G01X50503Y-233064D02*
X52383D01*
G01X51443D02*
Y-239364D01*
G01X50503D02*
X52383D01*
G01X59310D02*
X56176D01*
Y-233064D01*
X59310D01*
G01X58056Y-236109D02*
X56176D01*
G01X62241Y-239364D02*
Y-233064D01*
X65845Y-239364D01*
Y-233064D01*
G01X70186Y-240519D02*
X70500Y-239154D01*
G01X76643Y-233064D02*
Y-239364D01*
G01X74841Y-233064D02*
X78445D01*
G01X80985Y-239364D02*
X82943Y-233064D01*
X84901Y-239364D01*
G01X84196Y-237159D02*
X81690D01*
G01X88303Y-233064D02*
X90183D01*
G01X89243D02*
Y-239364D01*
G01X88303D02*
X90183D01*
G01X93193Y-233064D02*
X94290Y-239364D01*
X95543Y-233064D01*
X96796Y-239364D01*
X97893Y-233064D01*
G01X99885Y-239364D02*
X101843Y-233064D01*
X103801Y-239364D01*
G01X103096Y-237159D02*
X100590D01*
G01X106341Y-239364D02*
Y-233064D01*
X109945Y-239364D01*
Y-233064D01*
G01X119176Y-239364D02*
Y-233064D01*
X121135D01*
X121761Y-233379D01*
X122153Y-233799D01*
X122310Y-234639D01*
X122153Y-235479D01*
X121683Y-236004D01*
X121135Y-236319D01*
X119176D01*
G01X121135D02*
X122310Y-239364D01*
G01X127043Y-239574D02*
X126886Y-239469D01*
Y-239259D01*
X127043Y-239154D01*
X127200Y-239259D01*
Y-239469D01*
X127043Y-239574D01*
G01X133343Y-239364D02*
X132716Y-239259D01*
X132168Y-238839D01*
X131698Y-238209D01*
X131385Y-237474D01*
X131228Y-236634D01*
Y-235794D01*
X131385Y-234954D01*
X131698Y-234219D01*
X132168Y-233589D01*
X132716Y-233169D01*
X133343Y-233064D01*
X133970Y-233169D01*
X134518Y-233589D01*
X134988Y-234219D01*
X135301Y-234954D01*
X135458Y-235794D01*
Y-236634D01*
X135301Y-237474D01*
X134988Y-238209D01*
X134518Y-238839D01*
X133970Y-239259D01*
X133343Y-239364D01*
G01X139643Y-239574D02*
X139486Y-239469D01*
Y-239259D01*
X139643Y-239154D01*
X139800Y-239259D01*
Y-239469D01*
X139643Y-239574D01*
G01X147666Y-233589D02*
X147196Y-233274D01*
X146648Y-233064D01*
X146021D01*
X145316Y-233379D01*
X144768Y-233904D01*
X144376Y-234534D01*
X144063Y-235584D01*
X143985Y-236529D01*
X144141Y-237474D01*
X144376Y-238104D01*
X144846Y-238734D01*
X145395Y-239154D01*
X145943Y-239364D01*
X146491D01*
X147040Y-239154D01*
X147510Y-238839D01*
X147901Y-238419D01*
G01X152243Y-239574D02*
X152086Y-239469D01*
Y-239259D01*
X152243Y-239154D01*
X152400Y-239259D01*
Y-239469D01*
X152243Y-239574D01*
G01X37120Y-229364D02*
Y-223064D01*
G01X40096D02*
X37120Y-226949D01*
G01X40566Y-229364D02*
X38451Y-225164D01*
G01X43420Y-223064D02*
Y-227579D01*
X43733Y-228524D01*
X44360Y-229154D01*
X45143Y-229364D01*
X45926Y-229154D01*
X46553Y-228524D01*
X46866Y-227579D01*
Y-223064D01*
G01X53010Y-229364D02*
X49876D01*
Y-223064D01*
X53010D01*
G01X51756Y-226109D02*
X49876D01*
G01X56803Y-223064D02*
X58683D01*
G01X57743D02*
Y-229364D01*
G01X56803D02*
X58683D01*
G01X68698Y-228524D02*
X69325Y-229049D01*
X70030Y-229364D01*
X70656D01*
X71283Y-229049D01*
X71753Y-228524D01*
X71988Y-227789D01*
X71831Y-227054D01*
X71440Y-226424D01*
X70735Y-226004D01*
X69795Y-225794D01*
X69246Y-225374D01*
X69011Y-224639D01*
X69168Y-223904D01*
X69560Y-223379D01*
X70108Y-223064D01*
X70656D01*
X71205Y-223274D01*
X71675Y-223799D01*
G01X74998Y-229364D02*
Y-223064D01*
G01X78288D02*
Y-229364D01*
G01Y-226214D02*
X74998D01*
G01X80985Y-229364D02*
X82943Y-223064D01*
X84901Y-229364D01*
G01X84196Y-227159D02*
X81690D01*
G01X87441Y-229364D02*
Y-223064D01*
X91045Y-229364D01*
Y-223064D01*
G01X100198Y-229364D02*
Y-223064D01*
G01X103488D02*
Y-229364D01*
G01Y-226214D02*
X100198D01*
G01X106498Y-228524D02*
X107125Y-229049D01*
X107830Y-229364D01*
X108456D01*
X109083Y-229049D01*
X109553Y-228524D01*
X109788Y-227789D01*
X109631Y-227054D01*
X109240Y-226424D01*
X108535Y-226004D01*
X107595Y-225794D01*
X107046Y-225374D01*
X106811Y-224639D01*
X106968Y-223904D01*
X107360Y-223379D01*
X107908Y-223064D01*
X108456D01*
X109005Y-223274D01*
X109475Y-223799D01*
G01X113503Y-223064D02*
X115383D01*
G01X114443D02*
Y-229364D01*
G01X113503D02*
X115383D01*
G01X118785D02*
X120743Y-223064D01*
X122701Y-229364D01*
G01X121996Y-227159D02*
X119490D01*
G01X125241Y-229364D02*
Y-223064D01*
X128845Y-229364D01*
Y-223064D01*
G01X133813Y-226214D02*
X135380D01*
Y-228104D01*
X134910Y-228734D01*
X134361Y-229154D01*
X133578Y-229364D01*
X132795Y-229154D01*
X132246Y-228734D01*
X131776Y-228104D01*
X131463Y-227369D01*
X131306Y-226529D01*
Y-225794D01*
X131463Y-225164D01*
X131776Y-224429D01*
X132246Y-223799D01*
X132716Y-223379D01*
X133343Y-223064D01*
X133891D01*
X134518Y-223274D01*
X134988Y-223694D01*
G01X139486Y-230519D02*
X139800Y-229154D01*
G01X145943Y-223064D02*
Y-229364D01*
G01X144141Y-223064D02*
X147745D01*
G01X150285Y-229364D02*
X152243Y-223064D01*
X154201Y-229364D01*
G01X153496Y-227159D02*
X150990D01*
G01X158543Y-229364D02*
X157916Y-229259D01*
X157368Y-228839D01*
X156898Y-228209D01*
X156585Y-227474D01*
X156428Y-226634D01*
Y-225794D01*
X156585Y-224954D01*
X156898Y-224219D01*
X157368Y-223589D01*
X157916Y-223169D01*
X158543Y-223064D01*
X159170Y-223169D01*
X159718Y-223589D01*
X160188Y-224219D01*
X160501Y-224954D01*
X160658Y-225794D01*
Y-226634D01*
X160501Y-227474D01*
X160188Y-228209D01*
X159718Y-228839D01*
X159170Y-229259D01*
X158543Y-229364D01*
G01X171143D02*
Y-226529D01*
X169576Y-223064D01*
G01X172710D02*
X171143Y-226529D01*
G01X175720Y-223064D02*
Y-227579D01*
X176033Y-228524D01*
X176660Y-229154D01*
X177443Y-229364D01*
X178226Y-229154D01*
X178853Y-228524D01*
X179166Y-227579D01*
Y-223064D01*
G01X181785Y-229364D02*
X183743Y-223064D01*
X185701Y-229364D01*
G01X184996Y-227159D02*
X182490D01*
G01X188241Y-229364D02*
Y-223064D01*
X191845Y-229364D01*
Y-223064D01*
G01X37041Y-219364D02*
Y-213064D01*
X40645Y-219364D01*
Y-213064D01*
G01X45143Y-219364D02*
X44516Y-219259D01*
X43968Y-218839D01*
X43498Y-218209D01*
X43185Y-217474D01*
X43028Y-216634D01*
Y-215794D01*
X43185Y-214954D01*
X43498Y-214219D01*
X43968Y-213589D01*
X44516Y-213169D01*
X45143Y-213064D01*
X45770Y-213169D01*
X46318Y-213589D01*
X46788Y-214219D01*
X47101Y-214954D01*
X47258Y-215794D01*
Y-216634D01*
X47101Y-217474D01*
X46788Y-218209D01*
X46318Y-218839D01*
X45770Y-219259D01*
X45143Y-219364D01*
G01X51443Y-219574D02*
X51286Y-219469D01*
Y-219259D01*
X51443Y-219154D01*
X51600Y-219259D01*
Y-219469D01*
X51443Y-219574D01*
G01X57743Y-219364D02*
Y-213064D01*
X56803Y-214324D01*
G01Y-219364D02*
X58683D01*
G01X64043D02*
X64591Y-219259D01*
X65218Y-218944D01*
X65610Y-218419D01*
X65766Y-217684D01*
X65610Y-216949D01*
X65140Y-216319D01*
X64435Y-216004D01*
X63651D01*
X63181Y-215794D01*
X62790Y-215269D01*
X62633Y-214534D01*
X62868Y-213799D01*
X63416Y-213274D01*
X64043Y-213064D01*
X64670Y-213274D01*
X65218Y-213799D01*
X65453Y-214534D01*
X65296Y-215269D01*
X64905Y-215794D01*
X64435Y-216004D01*
X63651D01*
X62946Y-216319D01*
X62476Y-216949D01*
X62320Y-217684D01*
X62476Y-218419D01*
X62868Y-218944D01*
X63495Y-219259D01*
X64043Y-219364D01*
G01X70343D02*
X70891Y-219259D01*
X71518Y-218944D01*
X71910Y-218419D01*
X72066Y-217684D01*
X71910Y-216949D01*
X71440Y-216319D01*
X70735Y-216004D01*
X69951D01*
X69481Y-215794D01*
X69090Y-215269D01*
X68933Y-214534D01*
X69168Y-213799D01*
X69716Y-213274D01*
X70343Y-213064D01*
X70970Y-213274D01*
X71518Y-213799D01*
X71753Y-214534D01*
X71596Y-215269D01*
X71205Y-215794D01*
X70735Y-216004D01*
X69951D01*
X69246Y-216319D01*
X68776Y-216949D01*
X68620Y-217684D01*
X68776Y-218419D01*
X69168Y-218944D01*
X69795Y-219259D01*
X70343Y-219364D01*
G01X76486Y-220519D02*
X76800Y-219154D01*
G01X80593Y-213064D02*
X81690Y-219364D01*
X82943Y-213064D01*
X84196Y-219364D01*
X85293Y-213064D01*
G01X90810Y-219364D02*
X87676D01*
Y-213064D01*
X90810D01*
G01X89556Y-216109D02*
X87676D01*
G01X93741Y-219364D02*
Y-213064D01*
X97345Y-219364D01*
Y-213064D01*
G01X106498Y-219364D02*
Y-213064D01*
G01X109788D02*
Y-219364D01*
G01Y-216214D02*
X106498D01*
G01X112093Y-213064D02*
X113190Y-219364D01*
X114443Y-213064D01*
X115696Y-219364D01*
X116793Y-213064D01*
G01X118785Y-219364D02*
X120743Y-213064D01*
X122701Y-219364D01*
G01X121996Y-217159D02*
X119490D01*
G01X131855Y-214114D02*
X132325Y-213484D01*
X132873Y-213169D01*
X133500Y-213064D01*
X134283Y-213274D01*
X134831Y-213799D01*
X134988Y-214429D01*
X134910Y-215059D01*
X134596Y-215584D01*
X133030Y-216634D01*
X132325Y-217369D01*
X131855Y-218419D01*
X131698Y-219364D01*
X134988D01*
G01X137841D02*
Y-213064D01*
X141445Y-219364D01*
Y-213064D01*
G01X144220Y-219364D02*
Y-213064D01*
X145786D01*
X146413Y-213379D01*
X146883Y-213799D01*
X147275Y-214429D01*
X147588Y-215164D01*
X147666Y-216214D01*
X147588Y-217264D01*
X147275Y-217999D01*
X146883Y-218629D01*
X146413Y-219049D01*
X145786Y-219364D01*
X144220D01*
G01X156976D02*
Y-213064D01*
X158935D01*
X159561Y-213379D01*
X159953Y-213799D01*
X160110Y-214639D01*
X159953Y-215479D01*
X159483Y-216004D01*
X158935Y-216319D01*
X156976D01*
G01X158935D02*
X160110Y-219364D01*
G01X163120D02*
Y-213064D01*
X164686D01*
X165313Y-213379D01*
X165783Y-213799D01*
X166175Y-214429D01*
X166488Y-215164D01*
X166566Y-216214D01*
X166488Y-217264D01*
X166175Y-217999D01*
X165783Y-218629D01*
X165313Y-219049D01*
X164686Y-219364D01*
X163120D01*
G01X171143Y-219574D02*
X170986Y-219469D01*
Y-219259D01*
X171143Y-219154D01*
X171300Y-219259D01*
Y-219469D01*
X171143Y-219574D01*
G01X61143Y-206664D02*
X58623Y-206247D01*
X56418Y-204581D01*
X54528Y-202081D01*
X53268Y-199164D01*
X52638Y-195831D01*
Y-192497D01*
X53268Y-189164D01*
X54528Y-186247D01*
X56418Y-183748D01*
X58623Y-182081D01*
X61143Y-181664D01*
X63663Y-182081D01*
X65868Y-183748D01*
X67758Y-186247D01*
X69018Y-189164D01*
X69648Y-192497D01*
Y-195831D01*
X69018Y-199164D01*
X67758Y-202081D01*
X65868Y-204581D01*
X63663Y-206247D01*
X61143Y-206664D01*
G01X63663Y-199997D02*
X67443Y-206664D01*
G01X80988Y-189998D02*
Y-201664D01*
X82248Y-204581D01*
X84138Y-206247D01*
X86343Y-206664D01*
X88548Y-206247D01*
X90438Y-204581D01*
X91698Y-201664D01*
G01Y-206664D02*
Y-189998D01*
G01X117213Y-206664D02*
Y-189998D01*
G01Y-192914D02*
X115953Y-191248D01*
X114063Y-190414D01*
X111858Y-189998D01*
X109653Y-190831D01*
X107763Y-192497D01*
X106503Y-194998D01*
X105873Y-198331D01*
X106503Y-201664D01*
X107763Y-204165D01*
X109653Y-205831D01*
X111858Y-206664D01*
X114063Y-206247D01*
X115953Y-204998D01*
X117213Y-203331D01*
G01X131388Y-206664D02*
Y-189998D01*
G01Y-194164D02*
X132648Y-192081D01*
X134538Y-190414D01*
X137058Y-189998D01*
X139263Y-190414D01*
X141153Y-192081D01*
X142098Y-194998D01*
Y-206664D01*
G01X161943Y-181664D02*
Y-206664D01*
G01X157533Y-189998D02*
X166353D01*
G01X192813Y-206664D02*
Y-189998D01*
G01Y-192914D02*
X191553Y-191248D01*
X189663Y-190414D01*
X187458Y-189998D01*
X185253Y-190831D01*
X183363Y-192497D01*
X182103Y-194998D01*
X181473Y-198331D01*
X182103Y-201664D01*
X183363Y-204165D01*
X185253Y-205831D01*
X187458Y-206664D01*
X189663Y-206247D01*
X191553Y-204998D01*
X192813Y-203331D01*
G01X232493Y-186364D02*
Y-194364D01*
X236493D01*
G01X244293D02*
Y-189031D01*
G01Y-189964D02*
X243893Y-189431D01*
X243293Y-189164D01*
X242593Y-189031D01*
X241893Y-189297D01*
X241293Y-189831D01*
X240893Y-190631D01*
X240693Y-191697D01*
X240893Y-192764D01*
X241293Y-193564D01*
X241893Y-194097D01*
X242593Y-194364D01*
X243293Y-194231D01*
X243893Y-193831D01*
X244293Y-193298D01*
G01X248393Y-196764D02*
X248993Y-197031D01*
X249793Y-196764D01*
X250293Y-196231D01*
X250693Y-195564D01*
X251293Y-193431D01*
X252593Y-189031D01*
G01X249393D02*
X251293Y-193431D01*
G01X256993Y-190764D02*
X260193D01*
X259893Y-189831D01*
X259393Y-189297D01*
X258693Y-189031D01*
X257993Y-189164D01*
X257393Y-189564D01*
X256993Y-190497D01*
X256793Y-191298D01*
Y-192097D01*
X256993Y-192897D01*
X257493Y-193697D01*
X258093Y-194231D01*
X258793Y-194364D01*
X259493Y-194097D01*
X260193Y-193298D01*
G01X265093Y-194364D02*
Y-189031D01*
G01Y-190097D02*
X265593Y-189564D01*
X266093Y-189164D01*
X266793Y-189031D01*
X267293Y-189164D01*
X267893Y-189564D01*
G01X254793Y-236364D02*
X257193D01*
G01X255993D02*
Y-244364D01*
G01X254793D02*
X257193D01*
G01X262593D02*
Y-239031D01*
G01Y-240097D02*
X263093Y-239564D01*
X263593Y-239164D01*
X264293Y-239031D01*
X264793Y-239164D01*
X265393Y-239564D01*
G01X270493Y-240764D02*
X273693D01*
X273393Y-239831D01*
X272893Y-239297D01*
X272193Y-239031D01*
X271493Y-239164D01*
X270893Y-239564D01*
X270493Y-240497D01*
X270293Y-241298D01*
Y-242097D01*
X270493Y-242897D01*
X270993Y-243697D01*
X271593Y-244231D01*
X272293Y-244364D01*
X272993Y-244097D01*
X273693Y-243298D01*
G01X278293Y-244364D02*
Y-239031D01*
G01Y-240364D02*
X278693Y-239697D01*
X279293Y-239164D01*
X280093Y-239031D01*
X280793Y-239164D01*
X281393Y-239697D01*
X281693Y-240631D01*
Y-244364D01*
G01X286493Y-240764D02*
X289693D01*
X289393Y-239831D01*
X288893Y-239297D01*
X288193Y-239031D01*
X287493Y-239164D01*
X286893Y-239564D01*
X286493Y-240497D01*
X286293Y-241298D01*
Y-242097D01*
X286493Y-242897D01*
X286993Y-243697D01*
X287593Y-244231D01*
X288293Y-244364D01*
X288993Y-244097D01*
X289693Y-243298D01*
G01X245893Y-219364D02*
Y-211364D01*
X248493Y-218031D01*
X251093Y-211364D01*
Y-219364D01*
G01X253993D02*
X256493Y-211364D01*
X258993Y-219364D01*
G01X258093Y-216564D02*
X254893D01*
G01X262393Y-218298D02*
X263193Y-218964D01*
X264093Y-219364D01*
X264893D01*
X265693Y-218964D01*
X266293Y-218298D01*
X266593Y-217364D01*
X266393Y-216431D01*
X265893Y-215631D01*
X264993Y-215097D01*
X263793Y-214831D01*
X263093Y-214297D01*
X262793Y-213364D01*
X262993Y-212431D01*
X263493Y-211764D01*
X264193Y-211364D01*
X264893D01*
X265593Y-211631D01*
X266193Y-212297D01*
G01X270293Y-219364D02*
Y-211364D01*
G01X274093D02*
X270293Y-216298D01*
G01X274693Y-219364D02*
X271993Y-214031D01*
G01X279193Y-216697D02*
X281793D01*
G01X288493Y-211364D02*
Y-219364D01*
G01X286193Y-211364D02*
X290793D01*
G01X296493Y-219364D02*
X295693Y-219231D01*
X294993Y-218697D01*
X294393Y-217897D01*
X293993Y-216964D01*
X293793Y-215897D01*
Y-214831D01*
X293993Y-213764D01*
X294393Y-212831D01*
X294993Y-212031D01*
X295693Y-211497D01*
X296493Y-211364D01*
X297293Y-211497D01*
X297993Y-212031D01*
X298593Y-212831D01*
X298993Y-213764D01*
X299193Y-214831D01*
Y-215897D01*
X298993Y-216964D01*
X298593Y-217897D01*
X297993Y-218697D01*
X297293Y-219231D01*
X296493Y-219364D01*
G01X302493D02*
Y-211364D01*
X304893D01*
X305693Y-211764D01*
X306293Y-212697D01*
X306493Y-213764D01*
X306293Y-214831D01*
X305793Y-215631D01*
X304893Y-216031D01*
X302493D01*
G01X359093Y-237697D02*
X359693Y-236897D01*
X360393Y-236497D01*
X361193Y-236364D01*
X362193Y-236631D01*
X362893Y-237297D01*
X363093Y-238097D01*
X362993Y-238898D01*
X362593Y-239564D01*
X360593Y-240897D01*
X359693Y-241831D01*
X359093Y-243164D01*
X358893Y-244364D01*
X363093D01*
G01X368993Y-236364D02*
X368193Y-236631D01*
X367593Y-237297D01*
X367193Y-238097D01*
X366893Y-239164D01*
X366793Y-240364D01*
X366893Y-241564D01*
X367193Y-242631D01*
X367593Y-243431D01*
X368193Y-244097D01*
X368993Y-244364D01*
X369793Y-244097D01*
X370393Y-243431D01*
X370793Y-242631D01*
X371093Y-241564D01*
X371193Y-240364D01*
X371093Y-239164D01*
X370793Y-238097D01*
X370393Y-237297D01*
X369793Y-236631D01*
X368993Y-236364D01*
G01X376993Y-244364D02*
Y-236364D01*
X375793Y-237964D01*
G01Y-244364D02*
X378193D01*
G01X383093Y-237697D02*
X383693Y-236897D01*
X384393Y-236497D01*
X385193Y-236364D01*
X386193Y-236631D01*
X386893Y-237297D01*
X387093Y-238097D01*
X386993Y-238898D01*
X386593Y-239564D01*
X384593Y-240897D01*
X383693Y-241831D01*
X383093Y-243164D01*
X382893Y-244364D01*
X387093D01*
G01X391193Y-244631D02*
X394793Y-236364D01*
G01X400993Y-244364D02*
Y-236364D01*
X399793Y-237964D01*
G01Y-244364D02*
X402193D01*
G01X408993Y-236364D02*
X408193Y-236631D01*
X407593Y-237297D01*
X407193Y-238097D01*
X406893Y-239164D01*
X406793Y-240364D01*
X406893Y-241564D01*
X407193Y-242631D01*
X407593Y-243431D01*
X408193Y-244097D01*
X408993Y-244364D01*
X409793Y-244097D01*
X410393Y-243431D01*
X410793Y-242631D01*
X411093Y-241564D01*
X411193Y-240364D01*
X411093Y-239164D01*
X410793Y-238097D01*
X410393Y-237297D01*
X409793Y-236631D01*
X408993Y-236364D01*
G01X415193Y-244631D02*
X418793Y-236364D01*
G01X422793Y-242764D02*
X423393Y-243697D01*
X424193Y-244231D01*
X425093Y-244364D01*
X425893Y-244231D01*
X426693Y-243564D01*
X427193Y-242764D01*
X427293Y-241964D01*
X427093Y-241031D01*
X426393Y-240364D01*
X425693Y-240097D01*
X424793D01*
G01X425693D02*
X426293Y-239697D01*
X426793Y-239031D01*
X426993Y-238231D01*
X426793Y-237431D01*
X426293Y-236764D01*
X425393Y-236364D01*
X424493Y-236497D01*
X423593Y-237031D01*
G01X432993Y-244364D02*
Y-236364D01*
X431793Y-237964D01*
G01Y-244364D02*
X434193D01*
G01X358793Y-219364D02*
Y-211364D01*
X360793D01*
X361593Y-211764D01*
X362193Y-212297D01*
X362693Y-213097D01*
X363093Y-214031D01*
X363193Y-215364D01*
X363093Y-216697D01*
X362693Y-217631D01*
X362193Y-218431D01*
X361593Y-218964D01*
X360793Y-219364D01*
X358793D01*
G01X366493D02*
X368993Y-211364D01*
X371493Y-219364D01*
G01X370593Y-216564D02*
X367393D01*
G01X376993Y-211364D02*
Y-219364D01*
G01X374693Y-211364D02*
X379293D01*
G01X383093Y-216031D02*
X383793Y-215097D01*
X384393Y-214564D01*
X385193Y-214297D01*
X385893Y-214564D01*
X386393Y-215097D01*
X386793Y-215897D01*
X386893Y-216831D01*
X386793Y-217631D01*
X386393Y-218431D01*
X385793Y-219097D01*
X385093Y-219364D01*
X384293Y-219097D01*
X383593Y-218298D01*
X383193Y-217097D01*
X383093Y-215764D01*
X383293Y-214031D01*
X383593Y-213097D01*
X384093Y-212164D01*
X384793Y-211497D01*
X385493Y-211364D01*
X386193Y-211631D01*
X386693Y-212297D01*
G01X390393Y-219364D02*
Y-211364D01*
X392993Y-218031D01*
X395593Y-211364D01*
Y-219364D01*
G01X400993Y-211364D02*
Y-219364D01*
G01X398693Y-211364D02*
X403293D01*
G01X406893Y-219364D02*
Y-211364D01*
G01X411093D02*
Y-219364D01*
G01Y-215364D02*
X406893D01*
G01X414793Y-217764D02*
X415393Y-218697D01*
X416193Y-219231D01*
X417093Y-219364D01*
X417893Y-219231D01*
X418693Y-218564D01*
X419193Y-217764D01*
X419293Y-216964D01*
X419093Y-216031D01*
X418393Y-215364D01*
X417693Y-215097D01*
X416793D01*
G01X417693D02*
X418293Y-214697D01*
X418793Y-214031D01*
X418993Y-213231D01*
X418793Y-212431D01*
X418293Y-211764D01*
X417393Y-211364D01*
X416493Y-211497D01*
X415593Y-212031D01*
G01X422493Y-219364D02*
X424993Y-211364D01*
X427493Y-219364D01*
G01X426593Y-216564D02*
X423393D01*
G01X430793Y-219364D02*
Y-211364D01*
X432793D01*
X433593Y-211764D01*
X434193Y-212297D01*
X434693Y-213097D01*
X435093Y-214031D01*
X435193Y-215364D01*
X435093Y-216697D01*
X434693Y-217631D01*
X434193Y-218431D01*
X433593Y-218964D01*
X432793Y-219364D01*
X430793D01*
G01X440993Y-211364D02*
X440193Y-211631D01*
X439593Y-212297D01*
X439193Y-213097D01*
X438893Y-214164D01*
X438793Y-215364D01*
X438893Y-216564D01*
X439193Y-217631D01*
X439593Y-218431D01*
X440193Y-219097D01*
X440993Y-219364D01*
X441793Y-219097D01*
X442393Y-218431D01*
X442793Y-217631D01*
X443093Y-216564D01*
X443193Y-215364D01*
X443093Y-214164D01*
X442793Y-213097D01*
X442393Y-212297D01*
X441793Y-211631D01*
X440993Y-211364D01*
G01X380993Y-186364D02*
Y-194364D01*
G01X378693Y-186364D02*
X383293D01*
G01X387093Y-191031D02*
X387793Y-190097D01*
X388393Y-189564D01*
X389193Y-189297D01*
X389893Y-189564D01*
X390393Y-190097D01*
X390793Y-190897D01*
X390893Y-191831D01*
X390793Y-192631D01*
X390393Y-193431D01*
X389793Y-194097D01*
X389093Y-194364D01*
X388293Y-194097D01*
X387593Y-193298D01*
X387193Y-192097D01*
X387093Y-190764D01*
X387293Y-189031D01*
X387593Y-188097D01*
X388093Y-187164D01*
X388793Y-186497D01*
X389493Y-186364D01*
X390193Y-186631D01*
X390693Y-187297D01*
G01X394393Y-194364D02*
Y-186364D01*
X396993Y-193031D01*
X399593Y-186364D01*
Y-194364D01*
G01X401993Y-197031D02*
X407993D01*
G01X415193Y-187031D02*
X414593Y-186631D01*
X413893Y-186364D01*
X413093D01*
X412193Y-186764D01*
X411493Y-187431D01*
X410993Y-188231D01*
X410593Y-189564D01*
X410493Y-190764D01*
X410693Y-191964D01*
X410993Y-192764D01*
X411593Y-193564D01*
X412293Y-194097D01*
X412993Y-194364D01*
X413693D01*
X414393Y-194097D01*
X414993Y-193697D01*
X415493Y-193164D01*
G01X418393Y-194364D02*
Y-186364D01*
X420993Y-193031D01*
X423593Y-186364D01*
Y-194364D01*
G01X425993Y-197031D02*
X431993D01*
G01X434793Y-194364D02*
Y-186364D01*
X436793D01*
X437593Y-186764D01*
X438193Y-187297D01*
X438693Y-188097D01*
X439093Y-189031D01*
X439193Y-190364D01*
X439093Y-191697D01*
X438693Y-192631D01*
X438193Y-193431D01*
X437593Y-193964D01*
X436793Y-194364D01*
X434793D01*
G01X473793Y-244364D02*
Y-236364D01*
X475793D01*
X476593Y-236764D01*
X477193Y-237297D01*
X477693Y-238097D01*
X478093Y-239031D01*
X478193Y-240364D01*
X478093Y-241697D01*
X477693Y-242631D01*
X477193Y-243431D01*
X476593Y-243964D01*
X475793Y-244364D01*
X473793D01*
G01X503493D02*
Y-236364D01*
X502293Y-237964D01*
G01Y-244364D02*
X504693D01*
G01X509593Y-241031D02*
X510293Y-240097D01*
X510893Y-239564D01*
X511693Y-239297D01*
X512393Y-239564D01*
X512893Y-240097D01*
X513293Y-240897D01*
X513393Y-241831D01*
X513293Y-242631D01*
X512893Y-243431D01*
X512293Y-244097D01*
X511593Y-244364D01*
X510793Y-244097D01*
X510093Y-243298D01*
X509693Y-242097D01*
X509593Y-240764D01*
X509793Y-239031D01*
X510093Y-238097D01*
X510593Y-237164D01*
X511293Y-236497D01*
X511993Y-236364D01*
X512693Y-236631D01*
X513193Y-237297D01*
G54D156*
X523440Y462656D03*
G54D18*
X19987Y374226D03*
Y391942D03*
X32250Y374226D03*
Y391942D03*
G54D54*
X80553Y492338D03*
G54D183*
X683386Y626150D03*
X678386D03*
X673386D03*
Y661386D03*
X678386D03*
X683386D03*
X698386Y626150D03*
X693386D03*
X688386D03*
Y661386D03*
X693386D03*
X698386D03*
X713386Y626150D03*
X708386D03*
X703386D03*
Y661386D03*
X708386D03*
X713386D03*
X728386Y626150D03*
X723386D03*
X718386D03*
Y661386D03*
X723386D03*
X728386D03*
G54D147*
X478370Y104470D03*
Y113070D03*
G54D138*
X426950Y492873D03*
G54D45*
X69339Y515836D03*
Y513867D03*
Y511899D03*
Y509930D03*
X57135D03*
Y511899D03*
Y513867D03*
Y515836D03*
X119039Y402421D03*
X131245D03*
X119039Y404389D03*
Y406358D03*
X131245D03*
Y404389D03*
X119039Y410295D03*
X131245D03*
X119039Y408327D03*
X131245D03*
X636349Y300643D03*
Y308517D03*
Y302611D03*
Y304580D03*
Y306549D03*
X648555Y308517D03*
Y300643D03*
Y306549D03*
Y304580D03*
Y302611D03*
G54D174*
X642721Y384787D03*
Y409983D03*
X674155Y384787D03*
Y409983D03*
G54D90*
X164920Y259605D03*
Y337241D03*
X291778Y259605D03*
Y337241D03*
G54D72*
X149932Y40557D03*
G54D165*
X590999Y92789D03*
X615657D03*
G54D81*
X163195Y653433D03*
X179731D03*
X629669Y559245D03*
X646205D03*
G54D27*
X43898Y168544D03*
Y231457D03*
G54D129*
X414961Y98622D03*
G54D63*
X115150Y605559D03*
X110520Y627269D03*
X113270Y635559D03*
X111120Y657269D03*
X133410Y607269D03*
X143110Y612533D03*
X137230Y623734D03*
X150360Y622884D03*
X668320Y585031D03*
X666470Y593397D03*
X657270Y603848D03*
X667930Y599681D03*
X675130Y591687D03*
G54D36*
X55177Y805904D03*
X185098D03*
X252028D03*
X307146D03*
X413447D03*
X543368D03*
X610298D03*
X665416D03*
G54D64*
X136024Y145866D03*
X430906D03*
G54D19*
X20435Y561223D03*
X17876D03*
X15317D03*
X12758D03*
Y584223D03*
X15317D03*
X17876D03*
X20435D03*
X20507Y622914D03*
X17948D03*
X15389D03*
X12830D03*
X10271D03*
Y645914D03*
X12830D03*
X15389D03*
X17948D03*
X20507D03*
X36567Y79540D03*
X34008D03*
X31449D03*
Y102540D03*
X34008D03*
X36567D03*
X38349Y561223D03*
X35790D03*
X33231D03*
X30672D03*
X28112D03*
X25553D03*
X22994D03*
Y584223D03*
X25553D03*
X28112D03*
X30672D03*
X33231D03*
X35790D03*
X38349D03*
X38421Y622914D03*
X35862D03*
X33303D03*
X30744D03*
X28185D03*
X25625D03*
X23066D03*
Y645914D03*
X25625D03*
X28185D03*
X30744D03*
X33303D03*
X35862D03*
X38421D03*
X51922Y79540D03*
X49363D03*
X46803D03*
X44244D03*
X41685D03*
X39126D03*
Y102540D03*
X41685D03*
X44244D03*
X46803D03*
X49363D03*
X51922D03*
X46026Y561223D03*
X43467D03*
X40908D03*
Y584223D03*
X43467D03*
X46026D03*
X43539Y622914D03*
X40980D03*
Y645914D03*
X43539D03*
X64717Y79540D03*
X62158D03*
X59599D03*
X57040D03*
X54481D03*
Y102540D03*
X57040D03*
X59599D03*
X62158D03*
X64717D03*
G54D184*
X697200Y140140D03*
X693854D03*
X695084Y212132D03*
X698430D03*
G54D148*
X482093Y127519D03*
Y129487D03*
Y131456D03*
Y133424D03*
Y135393D03*
Y137361D03*
Y139330D03*
Y141298D03*
Y143267D03*
Y145235D03*
Y147204D03*
Y149172D03*
Y151141D03*
Y153109D03*
Y155078D03*
Y157046D03*
Y159015D03*
Y160983D03*
Y162952D03*
Y164920D03*
Y166889D03*
Y168857D03*
Y170826D03*
Y172794D03*
Y174763D03*
Y176731D03*
X573117Y139330D03*
Y137361D03*
Y135393D03*
Y133424D03*
Y131456D03*
Y129487D03*
Y127519D03*
Y155078D03*
Y153109D03*
Y151141D03*
Y149172D03*
Y147204D03*
Y145235D03*
Y143267D03*
Y141298D03*
Y170826D03*
Y168857D03*
Y166889D03*
Y164920D03*
Y162952D03*
Y160983D03*
Y159015D03*
Y157046D03*
Y176731D03*
Y174763D03*
Y172794D03*
G54D157*
X519985Y526639D03*
X525085Y522183D03*
G54D37*
X59920Y170026D03*
X65696Y170071D03*
X59920Y175826D03*
X65696Y175871D03*
X59821Y193765D03*
Y199565D03*
X65821D03*
Y193765D03*
X60242Y212743D03*
Y218543D03*
X66242D03*
Y212743D03*
X71880Y195309D03*
Y201109D03*
X77368Y295057D03*
Y289257D03*
X116165Y562839D03*
Y568639D03*
X124628Y726984D03*
Y732784D03*
X141699Y25494D03*
Y31294D03*
X151101Y455287D03*
Y449487D03*
X292893Y72444D03*
Y66644D03*
X298293Y72444D03*
Y66644D03*
X303693Y72444D03*
Y66644D03*
X367531Y641507D03*
Y635707D03*
X416288Y512677D03*
Y506877D03*
X421788Y512677D03*
Y506877D03*
X438258Y548889D03*
Y543089D03*
X454641Y518021D03*
Y523821D03*
X456991Y547728D03*
Y553628D03*
X542248Y97186D03*
Y102986D03*
X547340Y473756D03*
Y479556D03*
X560938Y106523D03*
Y100723D03*
X562340Y475256D03*
Y481056D03*
X585805Y201406D03*
Y207206D03*
X718231Y568773D03*
Y574573D03*
G54D46*
X66190Y506781D03*
X64221D03*
X62253D03*
X60284D03*
Y518985D03*
X62253D03*
X64221D03*
X66190D03*
X116698Y493127D03*
Y505333D03*
X124572Y493127D03*
X122604D03*
X120635D03*
X118666D03*
X124572Y505333D03*
X118666D03*
X120635D03*
X122604D03*
X334362Y550203D03*
X326488D03*
X332394D03*
X330425D03*
X328456D03*
X326488Y562409D03*
X334362D03*
X328456D03*
X330425D03*
X332394D03*
X379286Y524166D03*
X371412D03*
X377318D03*
X375349D03*
X373380D03*
X371412Y536372D03*
X379286D03*
X373380D03*
X375349D03*
X377318D03*
X458200Y81713D03*
X450326D03*
Y93919D03*
X458200D03*
X456232Y81713D03*
X454263D03*
X452294D03*
Y93919D03*
X454263D03*
X456232D03*
G54D82*
X164993Y705542D03*
Y700542D03*
Y695542D03*
Y710542D03*
G54D139*
X428628Y521153D03*
X427053D03*
X425478D03*
X423903D03*
X422329D03*
X420754D03*
X419179D03*
X417604D03*
Y541035D03*
X419179D03*
X420754D03*
X422329D03*
X423903D03*
X425478D03*
X427053D03*
X428628D03*
G54D175*
X643071Y386361D03*
Y387936D03*
Y389511D03*
Y391086D03*
Y392661D03*
Y394235D03*
Y395810D03*
Y397385D03*
Y398960D03*
Y400535D03*
Y402109D03*
Y403684D03*
Y405259D03*
Y406834D03*
Y408409D03*
X673805Y391086D03*
Y389511D03*
Y387936D03*
Y386361D03*
Y406834D03*
Y405259D03*
Y403684D03*
Y402109D03*
Y400535D03*
Y398960D03*
Y397385D03*
Y395810D03*
Y394235D03*
Y392661D03*
Y408409D03*
G54D28*
X41930Y184229D03*
G54D91*
X180546Y432984D03*
X275974Y25379D03*
X310327Y609214D03*
X402920Y609350D03*
G54D73*
X151969Y98622D03*
G54D166*
X584166Y276414D03*
X591774Y284989D03*
G54D55*
X74621Y493618D03*
G54D176*
X658438Y397385D03*
G54D47*
X70066Y560821D03*
X70220Y552972D03*
X70066Y576821D03*
Y568821D03*
X84989Y542702D03*
X77546Y560821D03*
X77700Y552972D03*
X77546Y576821D03*
Y568821D03*
X97605Y435943D03*
X90125D03*
X97605Y426943D03*
X90125D03*
X97627Y444943D03*
X90147D03*
X102240Y542702D03*
X92469D03*
X109720D03*
X240130Y418256D03*
X232650D03*
X240195Y434135D03*
X232715D03*
X240195Y426135D03*
X232715D03*
X250678Y608063D03*
X258158D03*
X250703Y623716D03*
X258183D03*
X250678Y615871D03*
X258158D03*
X313297Y546404D03*
X320777D03*
X321848Y571803D03*
X335123Y10530D03*
X327643D03*
X335123Y26530D03*
X327643D03*
X335123Y18530D03*
X327643D03*
X329328Y571803D03*
X351910Y331176D03*
X344430D03*
X343632Y613013D03*
X351112D03*
X343632Y605013D03*
X351112D03*
X343632Y621013D03*
X351112D03*
X417881Y412830D03*
X410401D03*
X417881Y420830D03*
X410401D03*
X417881Y436830D03*
X410401D03*
X417881Y428830D03*
X410401D03*
X417881Y444830D03*
X410401D03*
X410551Y452830D03*
X403071D03*
X410551Y460574D03*
X403071D03*
X409942Y631847D03*
X417422D03*
X463867Y587570D03*
X456387D03*
X555998Y222533D03*
X563478D03*
X617872Y526967D03*
X610392D03*
X638602Y317360D03*
X638592Y324998D03*
X646082Y317360D03*
X646072Y324998D03*
X669690Y193115D03*
X666118Y304444D03*
X658638D03*
X677170Y193115D03*
X695683Y562356D03*
X695668Y578380D03*
Y570380D03*
Y586380D03*
X710585Y543908D03*
X703105D03*
X703163Y562356D03*
X703148Y578380D03*
Y570380D03*
Y586380D03*
X757490Y105176D03*
X750010D03*
X758937Y577664D03*
X758928Y585787D03*
X766417Y577664D03*
X766408Y585787D03*
G54D149*
X495125Y118424D03*
X493156D03*
X491188D03*
Y185826D03*
X493156D03*
X495125D03*
X510873Y118424D03*
X508904D03*
X506936D03*
X504967D03*
X502999D03*
X501030D03*
X499062D03*
X497093D03*
Y185826D03*
X499062D03*
X501030D03*
X502999D03*
X504967D03*
X506936D03*
X508904D03*
X510873D03*
X526621Y118424D03*
X524652D03*
X522684D03*
X520715D03*
X518747D03*
X516778D03*
X514810D03*
X512841D03*
Y185826D03*
X514810D03*
X516778D03*
X518747D03*
X520715D03*
X522684D03*
X524652D03*
X526621D03*
X542369Y118424D03*
X540400D03*
X538432D03*
X536463D03*
X534495D03*
X532526D03*
X530558D03*
X528589D03*
Y185826D03*
X530558D03*
X532526D03*
X534495D03*
X536463D03*
X538432D03*
X540400D03*
X542369D03*
X558117Y118424D03*
X556148D03*
X554180D03*
X552211D03*
X550243D03*
X548274D03*
X546306D03*
X544337D03*
Y185826D03*
X546306D03*
X548274D03*
X550243D03*
X552211D03*
X554180D03*
X556148D03*
X558117D03*
X564022Y118424D03*
X562054D03*
X560085D03*
Y185826D03*
X562054D03*
X564022D03*
G54D38*
X65684Y233920D03*
X65974Y247944D03*
X76210Y163577D03*
X85010Y167577D03*
Y159577D03*
X77944Y181967D03*
X86744Y185967D03*
Y177967D03*
X77944Y195733D03*
X86744Y199733D03*
Y191733D03*
X81873Y209852D03*
X74484Y229920D03*
X81933Y223734D03*
X74484Y237920D03*
X74774Y251944D03*
Y243944D03*
X90733Y219734D03*
X90673Y213852D03*
Y205852D03*
X90733Y227734D03*
X133447Y667464D03*
Y675464D03*
X144203Y15162D03*
X135403Y11162D03*
Y19162D03*
X142247Y671464D03*
X179419Y667816D03*
X170619Y663816D03*
Y671816D03*
X425881Y631477D03*
X434681Y627477D03*
Y635477D03*
X491413Y214434D03*
X482613Y210434D03*
Y218434D03*
X746023Y450832D03*
X737223Y446832D03*
Y454832D03*
G54D92*
X177593Y438791D03*
X179562D03*
Y427177D03*
X177593D03*
X181530Y438791D03*
X183499D03*
Y427177D03*
X181530D03*
X273021Y31186D03*
Y19572D03*
X274990Y31186D03*
X276958D03*
X278927D03*
Y19572D03*
X276958D03*
X274990D03*
X313280Y603407D03*
X311311D03*
X309343D03*
X307374D03*
Y615021D03*
X309343D03*
X311311D03*
X313280D03*
X399967Y603543D03*
Y615157D03*
X405873Y603543D03*
X403904D03*
X401936D03*
Y615157D03*
X403904D03*
X405873D03*
G54D74*
X143617Y453259D03*
Y450700D03*
Y448141D03*
Y445582D03*
X258863Y632992D03*
Y635551D03*
Y638110D03*
Y640669D03*
G54D83*
X176939Y29820D03*
X174380D03*
X171820D03*
X169261D03*
Y46284D03*
G54D56*
X84103Y506011D03*
X158165Y24372D03*
X160111Y59871D03*
X179544Y418327D03*
X274972Y10722D03*
X311329Y623871D03*
X380699Y543426D03*
X406150Y510810D03*
X403922Y624007D03*
X446334Y543349D03*
X620366Y295775D03*
G54D29*
X45282Y338300D03*
G54D158*
X554780Y38803D03*
X617371D03*
X679963D03*
G54D65*
X125142Y406358D03*
X642452Y304580D03*
G54D185*
X685246Y592423D03*
G54D167*
X595427Y501238D03*
Y516986D03*
X622199Y501238D03*
Y516986D03*
X632769Y527813D03*
Y543561D03*
X659541Y527813D03*
Y543561D03*
G54D57*
X88150Y575352D03*
X97150D03*
X106150D03*
G54D48*
X68489Y603914D03*
Y608914D03*
Y613914D03*
Y623914D03*
Y628914D03*
Y618914D03*
Y633914D03*
Y638914D03*
Y643914D03*
Y653914D03*
Y658914D03*
Y648914D03*
X103725Y603914D03*
Y608914D03*
Y613914D03*
Y623914D03*
Y628914D03*
Y618914D03*
Y633914D03*
Y638914D03*
Y643914D03*
Y653914D03*
Y658914D03*
Y648914D03*
G54D186*
X711575Y143555D03*
Y195355D03*
Y222361D03*
Y274161D03*
X733975Y143555D03*
Y195355D03*
Y222361D03*
Y274161D03*
G54D93*
X174739Y430031D03*
Y432000D03*
Y433968D03*
Y435937D03*
X186353D03*
Y433968D03*
Y432000D03*
Y430031D03*
X270167Y22426D03*
Y24395D03*
Y26363D03*
Y28332D03*
X281781D03*
Y26363D03*
Y24395D03*
Y22426D03*
X304520Y606261D03*
Y608230D03*
Y610198D03*
Y612167D03*
X316134D03*
Y610198D03*
Y608230D03*
Y606261D03*
X397113Y606397D03*
Y608366D03*
Y610334D03*
Y612303D03*
X408727D03*
Y610334D03*
Y608366D03*
Y606397D03*
G54D75*
X149540Y703042D03*
G54D177*
X662460Y149432D03*
Y145496D03*
X662673Y164035D03*
Y160099D03*
X662294Y228238D03*
Y224302D03*
X662908Y242841D03*
Y238905D03*
X673484Y149432D03*
Y145496D03*
X673697Y164035D03*
Y160099D03*
X673318Y228238D03*
Y224302D03*
X673932Y242841D03*
Y238905D03*
G54D66*
X136097Y449421D03*
G54D159*
X546181Y81889D03*
G54D84*
X174380Y46284D03*
G54D168*
X605796Y165160D03*
X609733Y215672D03*
G54D39*
X57994Y278657D03*
X73742D03*
G54D67*
X120072Y477093D03*
Y484573D03*
X132152Y497692D03*
Y505172D03*
X223314Y62441D03*
Y54961D03*
X231314Y62441D03*
Y54961D03*
X239314Y62441D03*
Y54961D03*
X247314Y62441D03*
Y54961D03*
X252243Y640444D03*
Y632964D03*
X374786Y508277D03*
Y515757D03*
X387362Y548675D03*
Y541195D03*
X424904Y598298D03*
Y590818D03*
X443704Y110425D03*
X435937Y110553D03*
X443704Y117905D03*
X435937Y118033D03*
X459174Y110350D03*
X451401Y110425D03*
X459174Y117830D03*
X451401Y117905D03*
X554740Y473916D03*
Y481396D03*
X571175Y199691D03*
Y207171D03*
X579175Y199691D03*
Y207171D03*
G54D76*
X163583Y82480D03*
X161221D03*
X158859D03*
X162402Y114763D03*
X160040D03*
X180119Y82480D03*
X177757D03*
X175394D03*
X173032D03*
X170670D03*
X168308D03*
X165946D03*
X178938Y114763D03*
X176576D03*
X174213D03*
X171851D03*
X169489D03*
X167127D03*
X164765D03*
X194292Y82480D03*
X191930D03*
X189568D03*
X187205D03*
X184843D03*
X182481D03*
X195473Y114763D03*
X193111D03*
X190749D03*
X188387D03*
X186024D03*
X183662D03*
X181300D03*
X210827Y82480D03*
X208465D03*
X206103D03*
X203741D03*
X201379D03*
X199016D03*
X196654D03*
X209646Y114763D03*
X207284D03*
X204922D03*
X202560D03*
X200198D03*
X197835D03*
X227363Y82480D03*
X225001D03*
X222639D03*
X220276D03*
X217914D03*
X215552D03*
X213190D03*
X226182Y114763D03*
X223820D03*
X221457D03*
X219095D03*
X216733D03*
X214371D03*
X212009D03*
X241536Y82480D03*
X239174D03*
X236812D03*
X234450D03*
X232087D03*
X229725D03*
X242717Y114763D03*
X240355D03*
X237993D03*
X235631D03*
X233268D03*
X230906D03*
X228544D03*
X258072Y82480D03*
X255709D03*
X253347D03*
X259253Y114763D03*
X256891D03*
X254528D03*
X274607Y82480D03*
X272245D03*
X269883D03*
X267520D03*
X265158D03*
X262796D03*
X260434D03*
X273426Y114763D03*
X271064D03*
X268702D03*
X266339D03*
X263977D03*
X261615D03*
X288780Y82480D03*
X286418D03*
X284056D03*
X281694D03*
X279331D03*
X276969D03*
X289961Y114763D03*
X287599D03*
X285237D03*
X282875D03*
X280513D03*
X278150D03*
X275788D03*
X305316Y82480D03*
X302953D03*
X300591D03*
X298229D03*
X295867D03*
X293505D03*
X291142D03*
X306497Y114763D03*
X304135D03*
X301772D03*
X299410D03*
X297048D03*
X294686D03*
X292324D03*
X321851Y82480D03*
X319489D03*
X317127D03*
X314765D03*
X312402D03*
X310040D03*
X307678D03*
X320670Y114763D03*
X318308D03*
X315946D03*
X313583D03*
X311221D03*
X308859D03*
X336024Y82480D03*
X333662D03*
X331300D03*
X328938D03*
X326576D03*
X324213D03*
X337205Y114763D03*
X334843D03*
X332481D03*
X330119D03*
X327757D03*
X325394D03*
X323032D03*
X352560Y82480D03*
X350198D03*
X347835D03*
X345473D03*
X343111D03*
X340749D03*
X338387D03*
X353741Y114763D03*
X351379D03*
X349016D03*
X346654D03*
X344292D03*
X341930D03*
X339568D03*
X369095Y82480D03*
X366733D03*
X364371D03*
X362009D03*
X359646D03*
X357284D03*
X354922D03*
X367914Y114763D03*
X365552D03*
X363190D03*
X360827D03*
X358465D03*
X356103D03*
X383268Y82480D03*
X380906D03*
X378544D03*
X376182D03*
X373820D03*
X371457D03*
X384450Y114763D03*
X382087D03*
X379725D03*
X377363D03*
X375001D03*
X372639D03*
X370276D03*
X399804Y82480D03*
X397442D03*
X395079D03*
X392717D03*
X390355D03*
X387993D03*
X385631D03*
X400985Y114763D03*
X398623D03*
X396261D03*
X393898D03*
X391536D03*
X389174D03*
X386812D03*
X406891Y82480D03*
X404528D03*
X402166D03*
X408072Y114763D03*
X405709D03*
X403347D03*
G54D58*
X98426Y105512D03*
Y719685D03*
G54D94*
X173892Y482546D03*
X181470Y485105D03*
Y482546D03*
X173892Y487664D03*
X181470D03*
X506279Y209758D03*
Y214876D03*
X498701Y209758D03*
Y212317D03*
Y214876D03*
X506356Y219563D03*
Y224681D03*
X498778Y219563D03*
Y222122D03*
Y224681D03*
G54D169*
X605796Y174845D03*
G54D49*
X65740Y717159D03*
X67450Y727094D03*
X72170Y696299D03*
X70460Y707975D03*
X691990Y610622D03*
X684570Y615002D03*
G54D187*
X732284Y109187D03*
Y126509D03*
G54D85*
X173100Y40352D03*
G54D178*
X665457Y209073D03*
X682779D03*
G54D179*
X658936Y359552D03*
X673897D03*
G54D95*
X175463Y609933D03*
X633937Y602745D03*
G54D59*
X101399Y204167D03*
X98840D03*
Y218734D03*
X101399D03*
X106517Y204167D03*
X103958D03*
X106517Y218734D03*
X103958D03*
G54D68*
X127399Y522895D03*
X328448Y536761D03*
X645632Y284699D03*
G54D77*
X164375Y262559D03*
Y280287D03*
Y274623D03*
Y268223D03*
Y285951D03*
Y292351D03*
Y310079D03*
Y298015D03*
Y303679D03*
Y327807D03*
Y321407D03*
Y315743D03*
Y333471D03*
X292323Y263375D03*
Y269039D03*
Y281103D03*
Y275439D03*
Y286767D03*
Y293167D03*
Y304495D03*
Y310895D03*
Y298831D03*
Y328623D03*
Y322223D03*
Y316559D03*
Y334287D03*
G54D188*
X723275Y155655D03*
Y234461D03*
G54D86*
X173100Y33371D03*
G54D189*
X727607Y564179D03*
Y582179D03*
Y573179D03*
G54D69*
X132438Y699863D03*
X130470D03*
X128501D03*
Y717383D03*
X130470D03*
X132438D03*
X136375Y699863D03*
X134406D03*
Y717383D03*
X136375D03*
G54D96*
X186664Y43163D03*
X209694D03*
X199822Y427779D03*
X222852D03*
X268071Y614545D03*
X291101D03*
X294948Y20101D03*
X317978D03*
X361142Y611345D03*
X384172D03*
G54D78*
X163910Y507731D03*
X160760D03*
X157611D03*
X163910Y510881D03*
X160760D03*
X157611D03*
X163910Y514030D03*
X160760D03*
X157611D03*
X163910Y517180D03*
X160760D03*
X157611D03*
X163910Y520329D03*
X160760D03*
X157611D03*
X163910Y523479D03*
X160760D03*
X157611D03*
X163910Y526629D03*
X160760D03*
X157611D03*
X163910Y529778D03*
X160760D03*
X157611D03*
X163910Y532928D03*
X160760D03*
X157611D03*
X163910Y536077D03*
X160760D03*
X157611D03*
X163910Y539227D03*
X160760D03*
X157611D03*
X163910Y542377D03*
X160760D03*
X157611D03*
X163910Y545526D03*
X160760D03*
X157611D03*
X163910Y548676D03*
X160760D03*
X157611D03*
X163910Y551825D03*
X160760D03*
X157611D03*
X163910Y554975D03*
X160760D03*
X157611D03*
X179658Y507731D03*
X176508D03*
X179658Y510881D03*
X176508D03*
X179658Y514030D03*
X176508D03*
X179658Y517180D03*
X176508D03*
X179658Y520329D03*
X176508D03*
X179658Y523479D03*
X176508D03*
X179658Y526629D03*
X176508D03*
X179658Y529778D03*
X176508D03*
X179658Y532928D03*
X176508D03*
X179658Y536077D03*
X176508D03*
X179658Y539227D03*
X176508D03*
X179658Y542377D03*
X176508D03*
X179658Y545526D03*
X176508D03*
X179658Y548676D03*
X176508D03*
X179658Y551825D03*
X176508D03*
X179658Y554975D03*
X176508D03*
X182807Y507731D03*
Y510881D03*
Y514030D03*
Y517180D03*
Y520329D03*
Y523479D03*
Y526629D03*
Y529778D03*
Y532928D03*
Y536077D03*
Y539227D03*
Y542377D03*
Y545526D03*
Y548676D03*
Y551825D03*
Y554975D03*
X225755Y497872D03*
Y501022D03*
Y504171D03*
Y507321D03*
Y510471D03*
Y513620D03*
Y516770D03*
Y519919D03*
Y523069D03*
Y526219D03*
Y529368D03*
Y532518D03*
Y535667D03*
Y538817D03*
Y541967D03*
Y545116D03*
Y548266D03*
Y551415D03*
Y554565D03*
Y557715D03*
Y560864D03*
Y564014D03*
X228905Y497872D03*
Y501022D03*
X232054Y497872D03*
Y501022D03*
X235204Y497872D03*
Y501022D03*
X238354Y497872D03*
Y501022D03*
X241503Y497872D03*
Y501022D03*
X228905Y504171D03*
Y507321D03*
Y510471D03*
Y513620D03*
Y516770D03*
X232054Y504171D03*
Y507321D03*
Y510471D03*
Y513620D03*
Y516770D03*
X235204Y504171D03*
Y507321D03*
Y510471D03*
Y513620D03*
Y516770D03*
X238354Y504171D03*
Y507321D03*
Y510471D03*
Y513620D03*
Y516770D03*
X241503Y504171D03*
Y507321D03*
Y510471D03*
X228905Y519919D03*
Y523069D03*
Y526219D03*
Y529368D03*
Y532518D03*
X232054Y519919D03*
Y523069D03*
Y526219D03*
Y529368D03*
Y532518D03*
X235204Y519919D03*
Y523069D03*
Y526219D03*
Y529368D03*
Y532518D03*
X238354Y519919D03*
Y523069D03*
Y526219D03*
Y529368D03*
Y532518D03*
X241503Y519919D03*
Y523069D03*
Y526219D03*
Y529368D03*
Y532518D03*
X228905Y535667D03*
Y538817D03*
Y541967D03*
Y545116D03*
Y548266D03*
X232054Y535667D03*
Y538817D03*
Y541967D03*
Y545116D03*
Y548266D03*
X235204Y535667D03*
Y538817D03*
Y541967D03*
Y545116D03*
Y548266D03*
X238354Y535667D03*
Y538817D03*
Y541967D03*
Y545116D03*
Y548266D03*
X241503Y535667D03*
Y538817D03*
Y541967D03*
X228905Y551415D03*
Y554565D03*
Y557715D03*
Y560864D03*
Y564014D03*
X232054Y551415D03*
Y554565D03*
Y557715D03*
Y560864D03*
Y564014D03*
X235204Y551415D03*
Y554565D03*
Y557715D03*
Y560864D03*
Y564014D03*
X238354Y551415D03*
Y554565D03*
Y557715D03*
Y560864D03*
Y564014D03*
X241503Y551415D03*
Y554565D03*
Y557715D03*
Y560864D03*
Y564014D03*
X244653Y497872D03*
Y501022D03*
X247802Y497872D03*
Y501022D03*
X250952Y497872D03*
Y501022D03*
X254102Y497872D03*
Y501022D03*
X257251Y497872D03*
Y501022D03*
X244653Y504171D03*
Y507321D03*
Y510471D03*
X247802Y504171D03*
Y507321D03*
Y510471D03*
Y513620D03*
X250952Y504171D03*
Y507321D03*
Y510471D03*
Y513620D03*
X254102Y504171D03*
Y507321D03*
Y510471D03*
Y513620D03*
X257251Y504171D03*
Y507321D03*
Y510471D03*
Y513620D03*
X250952Y523069D03*
Y526219D03*
Y529368D03*
Y532518D03*
X254102Y523069D03*
Y526219D03*
Y529368D03*
Y532518D03*
X257251Y523069D03*
Y526219D03*
Y529368D03*
Y532518D03*
X247802Y548266D03*
X250952Y535667D03*
Y538817D03*
Y548266D03*
X254102Y535667D03*
Y538817D03*
Y548266D03*
X257251Y535667D03*
Y538817D03*
Y548266D03*
X244653Y551415D03*
Y554565D03*
Y557715D03*
Y560864D03*
Y564014D03*
X247802Y551415D03*
Y554565D03*
Y557715D03*
Y560864D03*
Y564014D03*
X250952Y551415D03*
Y554565D03*
Y557715D03*
Y560864D03*
Y564014D03*
X254102Y551415D03*
Y554565D03*
Y557715D03*
Y560864D03*
Y564014D03*
X257251Y551415D03*
Y554565D03*
Y557715D03*
Y560864D03*
Y564014D03*
X260401Y497872D03*
Y501022D03*
X263550Y497872D03*
Y501022D03*
X266700Y497872D03*
Y501022D03*
X269850Y497872D03*
Y501022D03*
X272999Y497872D03*
Y501022D03*
X260401Y504171D03*
Y507321D03*
Y510471D03*
Y513620D03*
X263550Y504171D03*
Y507321D03*
Y510471D03*
Y513620D03*
X266700Y504171D03*
Y507321D03*
Y510471D03*
Y513620D03*
X269850Y504171D03*
Y507321D03*
Y510471D03*
Y513620D03*
X272999Y504171D03*
Y507321D03*
Y510471D03*
X260401Y523069D03*
Y526219D03*
Y529368D03*
Y532518D03*
X263550Y523069D03*
Y526219D03*
Y529368D03*
Y532518D03*
X266700Y523069D03*
Y526219D03*
Y529368D03*
Y532518D03*
X260401Y535667D03*
Y538817D03*
Y548266D03*
X263550Y535667D03*
Y538817D03*
Y548266D03*
X266700Y535667D03*
Y538817D03*
Y548266D03*
X269850D03*
X260401Y551415D03*
Y554565D03*
Y557715D03*
Y560864D03*
Y564014D03*
X263550Y551415D03*
Y554565D03*
Y557715D03*
Y560864D03*
Y564014D03*
X266700Y551415D03*
Y554565D03*
Y557715D03*
Y560864D03*
Y564014D03*
X269850Y551415D03*
Y554565D03*
Y557715D03*
Y560864D03*
Y564014D03*
X272999Y551415D03*
Y554565D03*
Y557715D03*
Y560864D03*
Y564014D03*
X276149Y497872D03*
Y501022D03*
X279298Y497872D03*
Y501022D03*
X282448Y497872D03*
Y501022D03*
X285598Y497872D03*
Y501022D03*
X288747Y497872D03*
Y501022D03*
X276149Y504171D03*
Y507321D03*
Y510471D03*
X279298Y504171D03*
Y507321D03*
Y510471D03*
Y513620D03*
X282448Y504171D03*
Y507321D03*
Y510471D03*
Y513620D03*
X285598Y504171D03*
Y507321D03*
Y510471D03*
Y513620D03*
X288747Y504171D03*
Y507321D03*
Y510471D03*
Y513620D03*
X279298Y516770D03*
X282448D03*
X285598D03*
X288747D03*
X276149Y519919D03*
Y523069D03*
Y526219D03*
Y529368D03*
Y532518D03*
X279298Y519919D03*
Y523069D03*
Y526219D03*
Y529368D03*
Y532518D03*
X282448Y519919D03*
Y523069D03*
Y526219D03*
Y529368D03*
Y532518D03*
X285598Y519919D03*
Y523069D03*
Y526219D03*
Y529368D03*
Y532518D03*
X288747Y519919D03*
Y523069D03*
Y526219D03*
Y529368D03*
Y532518D03*
X276149Y535667D03*
Y538817D03*
Y541967D03*
X279298Y535667D03*
Y538817D03*
Y541967D03*
Y545116D03*
Y548266D03*
X282448Y535667D03*
Y538817D03*
Y541967D03*
Y545116D03*
Y548266D03*
X285598Y535667D03*
Y538817D03*
Y541967D03*
Y545116D03*
Y548266D03*
X288747Y535667D03*
Y538817D03*
Y541967D03*
Y545116D03*
Y548266D03*
X276149Y551415D03*
Y554565D03*
Y557715D03*
Y560864D03*
Y564014D03*
X279298Y551415D03*
Y554565D03*
Y557715D03*
Y560864D03*
Y564014D03*
X282448Y551415D03*
Y554565D03*
Y557715D03*
Y560864D03*
Y564014D03*
X285598Y551415D03*
Y554565D03*
Y557715D03*
Y560864D03*
Y564014D03*
X288747Y551415D03*
Y554565D03*
Y557715D03*
Y560864D03*
Y564014D03*
X291897Y497872D03*
Y501022D03*
Y504171D03*
Y507321D03*
Y510471D03*
Y513620D03*
Y516770D03*
Y519919D03*
Y523069D03*
Y526219D03*
Y529368D03*
Y532518D03*
Y535667D03*
Y538817D03*
Y541967D03*
Y545116D03*
Y548266D03*
Y551415D03*
Y554565D03*
Y557715D03*
Y560864D03*
Y564014D03*
G54D87*
X164920Y246805D03*
Y250005D03*
X168120Y246805D03*
X171320D03*
X168120Y250005D03*
X171320D03*
X174520Y246805D03*
X164920Y256405D03*
Y253205D03*
X171320D03*
X168120D03*
X164920Y340441D03*
Y343641D03*
X171320D03*
X168120D03*
X174520Y350041D03*
X171320D03*
X168120Y346841D03*
X171320D03*
X285378Y246805D03*
Y250005D03*
X282178Y246805D03*
X288578D03*
Y250005D03*
X285378Y253205D03*
X288578D03*
X285378Y343641D03*
X288578D03*
X282178Y350041D03*
X285378Y346841D03*
X288578Y350041D03*
X285378D03*
X288578Y346841D03*
X291778Y246805D03*
Y250005D03*
Y256405D03*
Y253205D03*
Y340441D03*
Y343641D03*
Y350041D03*
Y346841D03*
G54D79*
X157550Y595169D03*
Y597138D03*
Y599106D03*
Y601075D03*
Y603043D03*
Y605012D03*
Y606980D03*
Y608949D03*
Y610917D03*
Y612886D03*
Y614854D03*
Y616823D03*
Y618791D03*
Y620760D03*
Y622728D03*
Y624697D03*
X193376Y597138D03*
Y595169D03*
Y612886D03*
Y610917D03*
Y608949D03*
Y606980D03*
Y605012D03*
Y603043D03*
Y601075D03*
Y599106D03*
Y624697D03*
Y622728D03*
Y620760D03*
Y618791D03*
Y616823D03*
Y614854D03*
X616024Y587981D03*
Y589950D03*
Y591918D03*
Y593887D03*
Y595855D03*
Y597824D03*
Y599792D03*
Y601761D03*
Y603729D03*
Y605698D03*
Y607666D03*
Y609635D03*
Y611603D03*
Y613572D03*
Y615540D03*
Y617509D03*
X651850Y595855D03*
Y593887D03*
Y591918D03*
Y589950D03*
Y587981D03*
Y611603D03*
Y609635D03*
Y607666D03*
Y605698D03*
Y603729D03*
Y601761D03*
Y599792D03*
Y597824D03*
Y617509D03*
Y615540D03*
Y613572D03*
G54D88*
X177720Y246805D03*
Y350041D03*
X278978Y246805D03*
Y350041D03*
G54D97*
X193300Y246260D03*
X187636D03*
X181236D03*
X180422Y350586D03*
X186822D03*
X192486D03*
X211028Y246260D03*
X205364D03*
X198964D03*
X204550Y350586D03*
X198150D03*
X210214D03*
X216692Y246260D03*
X223092D03*
X222278Y350586D03*
X215878D03*
X234420Y246260D03*
X240820D03*
X228756D03*
X227942Y350586D03*
X240006D03*
X233606D03*
X252148Y246260D03*
X246484D03*
X258548D03*
X245670Y350586D03*
X251334D03*
X257734D03*
X269876Y246260D03*
X264212D03*
X263398Y350586D03*
X269062D03*
X276276Y246260D03*
X275462Y350586D03*
G54D98*
X197429Y393326D03*
G54D89*
X175572Y249980D03*
X178812Y257697D03*
X169684Y255495D03*
X168121Y257802D03*
X170272Y259883D03*
X172982Y260548D03*
X173177Y257783D03*
X177312Y260229D03*
X175812Y265293D03*
X178812D03*
X171095Y262559D03*
X168095Y262759D03*
X166332Y265399D03*
X170102Y265191D03*
X172982Y264570D03*
X175572Y252980D03*
X177583Y254867D03*
X178248Y252157D03*
X173561Y254867D03*
X177312Y273113D03*
Y275869D03*
X175812Y268049D03*
X178812D03*
X166778Y269599D03*
X169684Y269723D03*
X168338Y267316D03*
X172426Y270085D03*
X172914Y267355D03*
X172426Y272841D03*
X173177Y275511D03*
X169684Y273223D03*
X168321Y275630D03*
X166771Y273247D03*
X172982Y278276D03*
X170272Y277611D03*
X166122Y277297D03*
X168095Y280487D03*
X171095Y280287D03*
X178812Y280933D03*
X175812D03*
X177312Y288753D03*
X172914Y285083D03*
X168338Y285044D03*
X166332Y283127D03*
X178812Y283689D03*
X175812D03*
X172982Y282298D03*
X170102Y282919D03*
X172426Y287813D03*
X169684Y287451D03*
X166778Y287327D03*
X166771Y290975D03*
X172426Y290569D03*
X173177Y293239D03*
X168321Y293358D03*
X169684Y290951D03*
X177312Y291509D03*
X170272Y295339D03*
X166122Y295025D03*
X172982Y296004D03*
X175812Y296573D03*
X178812D03*
X168095Y298215D03*
X171095Y298015D03*
X172982Y300026D03*
X175812Y299329D03*
X178812D03*
X177312Y304393D03*
Y307149D03*
X168338Y302772D03*
X170102Y300647D03*
X166332Y300855D03*
X172914Y302811D03*
X166771Y308703D03*
X172426Y308297D03*
Y305541D03*
X173177Y310967D03*
X168321Y311086D03*
X169684Y308679D03*
Y305179D03*
X166778Y305055D03*
X178812Y312213D03*
X175812D03*
X170272Y313067D03*
X166122Y312753D03*
X178812Y314969D03*
X175812D03*
X172982Y313732D03*
X177312Y320033D03*
Y322789D03*
X175812Y327853D03*
X178812D03*
X172914Y320539D03*
X172982Y317754D03*
X168338Y320500D03*
X170102Y318375D03*
X166332Y318583D03*
X168095Y315943D03*
X171095Y315743D03*
X166771Y326431D03*
X172426Y323269D03*
X169684Y322907D03*
X166778Y322783D03*
X169684Y326407D03*
X168321Y328814D03*
X173177Y328695D03*
X172426Y326025D03*
X175812Y338429D03*
Y330609D03*
X178812D03*
X166122Y330481D03*
X170272Y330795D03*
X172982Y331460D03*
X171095Y333471D03*
X168095Y333671D03*
X170272Y336147D03*
X168121Y338228D03*
X172982Y335482D03*
X172914Y338267D03*
X172426Y340997D03*
X169684Y340535D03*
X179554Y342047D03*
X176768Y341979D03*
X179579Y336149D03*
Y339149D03*
X174757Y343866D03*
X177433Y344689D03*
X179515Y346623D03*
X174757Y346866D03*
X193100Y249980D03*
X180229Y250206D03*
X188543Y250223D03*
X182612Y248656D03*
X186260Y248663D03*
X190460Y248217D03*
X182636Y251569D03*
X186136D03*
X190668Y251987D03*
X180312Y260229D03*
X181812Y265293D03*
X193300Y252980D03*
X195311Y254867D03*
X191289D03*
X183279Y260697D03*
Y257697D03*
X191099Y259197D03*
Y265197D03*
Y262197D03*
X188343Y259197D03*
Y265197D03*
Y262197D03*
X180348Y255062D03*
X183018Y254311D03*
X185774D03*
X188504Y254826D03*
X189312Y273113D03*
Y275869D03*
X186312D03*
X183312D03*
X186312Y273113D03*
X183312D03*
X192312Y275869D03*
Y273113D03*
X187812Y268049D03*
X184812D03*
X180312Y275869D03*
Y273113D03*
X181812Y268049D03*
Y280933D03*
X184812D03*
X187812D03*
X190812D03*
X193812D03*
X191099Y268197D03*
X195312Y291509D03*
Y288753D03*
X180312D03*
Y291509D03*
X183312Y288753D03*
X186312D03*
X183312Y291509D03*
X186312D03*
X189312D03*
Y288753D03*
X192312D03*
Y291509D03*
X181812Y283689D03*
X184812D03*
X187812D03*
X190812D03*
X193812D03*
X181812Y296573D03*
X190812D03*
X187812D03*
X184812D03*
X193812D03*
X181812Y299329D03*
X190812D03*
X187812D03*
X184812D03*
X193812D03*
X195312Y304393D03*
Y307149D03*
X180312D03*
Y304393D03*
X189312D03*
Y307149D03*
X186312D03*
X183312D03*
X186312Y304393D03*
X183312D03*
X192312Y307149D03*
Y304393D03*
X181812Y312213D03*
X184812D03*
X187812D03*
X190812D03*
X193812D03*
X181812Y314969D03*
X184812D03*
X187812D03*
X190812D03*
X193812D03*
X183312Y320033D03*
X186312D03*
X189312D03*
X181812Y327853D03*
X183312Y322789D03*
X186312D03*
X189312D03*
X184812Y327853D03*
X187812D03*
X190812D03*
X192312Y320033D03*
Y322789D03*
X180312Y320033D03*
Y322789D03*
X195219Y321149D03*
Y324149D03*
Y327149D03*
X190475Y341979D03*
X187710Y341784D03*
X187399Y334649D03*
Y331649D03*
X190155Y334649D03*
Y331649D03*
Y337649D03*
X187399D03*
X182335Y333149D03*
Y336149D03*
Y339149D03*
X189810Y344689D03*
X194497Y341979D03*
X192486Y343866D03*
X182284Y342535D03*
X185040D03*
X195219Y330149D03*
Y333149D03*
Y336149D03*
Y339149D03*
X195118Y344859D03*
X189496Y348839D03*
X192686Y346866D03*
X185446Y348190D03*
X181922Y345277D03*
X185422D03*
X187829Y346640D03*
X181798Y348183D03*
X195326Y348629D03*
X210828Y249980D03*
X197957Y250206D03*
X206271Y250223D03*
X196290Y248007D03*
X200340Y248656D03*
X208188Y248217D03*
X203988Y248663D03*
X200364Y251569D03*
X208396Y251987D03*
X203864Y251569D03*
X211028Y252980D03*
X196163Y263697D03*
Y257697D03*
Y260697D03*
X198919Y263697D03*
Y257697D03*
Y260697D03*
X206739Y262197D03*
Y265197D03*
Y259197D03*
X203983Y262197D03*
Y265197D03*
Y259197D03*
X195976Y252157D03*
X200746Y254311D03*
X203502D03*
X198076Y255062D03*
X209017Y254867D03*
X206232Y254826D03*
X196812Y280933D03*
X199812D03*
X205118Y276767D03*
X201574D03*
X207874D03*
X196163Y275697D03*
Y272697D03*
Y269697D03*
X198919Y275697D03*
Y272697D03*
Y269697D03*
X206739Y268197D03*
Y271197D03*
Y274197D03*
X203983Y268197D03*
Y271197D03*
Y274197D03*
X196163Y266697D03*
X198919D03*
X198312Y288753D03*
Y291509D03*
X201068Y288753D03*
Y291509D03*
X201412Y294265D03*
Y285997D03*
X196812Y283689D03*
X199812D03*
X196812Y296573D03*
X199812D03*
X196812Y299329D03*
X199812D03*
X201412Y301637D03*
X201068Y304393D03*
Y307149D03*
X201412Y309905D03*
X198312Y307149D03*
Y304393D03*
X196812Y312213D03*
X199812D03*
X196812Y314969D03*
X199812D03*
X210859Y321149D03*
Y327149D03*
Y324149D03*
X207874Y320079D03*
X204724D03*
X201968D03*
X205795Y322649D03*
X203039D03*
Y325649D03*
X205795D03*
Y328649D03*
X203039D03*
X197975Y321149D03*
Y324149D03*
Y327149D03*
X201868Y317323D03*
X197282Y342047D03*
X205438Y341784D03*
X208203Y341979D03*
X210859Y336149D03*
Y333149D03*
Y330149D03*
Y339149D03*
X203039Y337649D03*
X205795D03*
Y331649D03*
Y334649D03*
X203039Y331649D03*
Y334649D03*
X197975Y330149D03*
Y333149D03*
Y336149D03*
Y339149D03*
X200012Y342535D03*
X207538Y344689D03*
X202768Y342535D03*
X210214Y343866D03*
X203174Y348190D03*
X197243Y346623D03*
X199650Y345277D03*
X199526Y348183D03*
X207224Y348839D03*
X205557Y346640D03*
X203150Y345277D03*
X210414Y346866D03*
X223999Y250223D03*
X215685Y250206D03*
X214018Y248007D03*
X218068Y248656D03*
X221716Y248663D03*
X225916Y248217D03*
X221592Y251569D03*
X218092D03*
X222379Y259197D03*
X219623D03*
Y265197D03*
Y262197D03*
X222379Y265197D03*
Y262197D03*
X214559Y260697D03*
Y257697D03*
Y263697D03*
X211803Y260697D03*
Y257697D03*
Y263697D03*
X213704Y252157D03*
X213039Y254867D03*
X223960Y254826D03*
X215804Y255062D03*
X221230Y254311D03*
X218474D03*
X226124Y251987D03*
X226745Y254867D03*
X220868Y276767D03*
X211803Y275697D03*
X214559D03*
X217324Y276767D03*
X223624D03*
X219623Y274197D03*
X222379D03*
Y271197D03*
X219623D03*
Y268197D03*
X222379D03*
X214559Y269697D03*
Y272697D03*
X211803Y269697D03*
Y272697D03*
X214559Y266697D03*
X211803D03*
X217324Y320079D03*
X223624D03*
X220080D03*
X218679Y328649D03*
X221435D03*
Y325649D03*
X218679D03*
Y322649D03*
X221435D03*
X213615Y321149D03*
Y327149D03*
Y324149D03*
X226499Y321149D03*
Y324149D03*
Y327149D03*
X223166Y341784D03*
X215010Y342047D03*
X212225Y341979D03*
X218679Y334649D03*
Y331649D03*
X221435Y334649D03*
Y331649D03*
Y337649D03*
X218679D03*
X213615Y336149D03*
Y333149D03*
Y330149D03*
Y339149D03*
X212846Y344859D03*
X217740Y342535D03*
X220496D03*
X225931Y341979D03*
X226499Y330149D03*
Y333149D03*
Y336149D03*
Y339149D03*
X225266Y344689D03*
X220902Y348190D03*
X213054Y348629D03*
X217254Y348183D03*
X224952Y348839D03*
X217378Y345277D03*
X220878D03*
X223285Y346640D03*
X214971Y346623D03*
X233413Y250206D03*
X241727Y250223D03*
X228556Y249980D03*
X235796Y248656D03*
X239444Y248663D03*
X231746Y248007D03*
X239320Y251569D03*
X235820D03*
X243083Y260697D03*
Y257697D03*
Y263697D03*
X230199D03*
Y257697D03*
Y260697D03*
X238019Y262197D03*
Y265197D03*
X235263Y262197D03*
Y265197D03*
Y259197D03*
X238019D03*
X231432Y252157D03*
X233532Y255062D03*
X230767Y254867D03*
X238958Y254311D03*
X236202D03*
X241688Y254826D03*
X228756Y252980D03*
X227443Y263697D03*
Y257697D03*
Y260697D03*
X236618Y276767D03*
X230199Y275697D03*
X243083D03*
X233074Y276767D03*
X239374D03*
X243083Y269697D03*
Y272697D03*
X230199D03*
Y269697D03*
X238019Y268197D03*
X235263D03*
Y271197D03*
X238019D03*
Y274197D03*
X235263D03*
X243083Y266697D03*
X230199D03*
X227443Y275697D03*
Y272697D03*
Y269697D03*
Y266697D03*
X242139Y321149D03*
Y327149D03*
Y324149D03*
X233074Y320079D03*
X239374D03*
X235830D03*
X237075Y322649D03*
X234319D03*
Y325649D03*
X237075D03*
Y328649D03*
X234319D03*
X229255Y321149D03*
Y324149D03*
Y327149D03*
X229953Y341979D03*
X232738Y342020D03*
X240894Y341784D03*
X242139Y336149D03*
Y333149D03*
Y330149D03*
Y339149D03*
X234319Y337649D03*
X237075D03*
Y331649D03*
Y334649D03*
X234319Y331649D03*
Y334649D03*
X229255Y330149D03*
Y333149D03*
Y336149D03*
Y339149D03*
X227942Y343866D03*
X242994Y344689D03*
X230574Y344859D03*
X235468Y342535D03*
X238224D03*
X228142Y346866D03*
X238630Y348190D03*
X242680Y348839D03*
X230782Y348629D03*
X234982Y348183D03*
X232699Y346623D03*
X235106Y345277D03*
X238606D03*
X241013Y346640D03*
X251141Y250206D03*
X253524Y248656D03*
X249474Y248007D03*
X246284Y249980D03*
X243644Y248217D03*
X257172Y248663D03*
X253548Y251569D03*
X243852Y251987D03*
X253659Y259197D03*
X250903D03*
Y265197D03*
Y262197D03*
X253659Y265197D03*
Y262197D03*
X249160Y252157D03*
X251260Y255062D03*
X248495Y254867D03*
X253930Y254311D03*
X246484Y252980D03*
X245839Y260697D03*
Y257697D03*
Y263697D03*
X244473Y254867D03*
X257048Y251569D03*
X258723Y263697D03*
Y257697D03*
Y260697D03*
X256686Y254311D03*
X254830Y279523D03*
X254730Y276767D03*
X251974D03*
X248824D03*
X250903Y274197D03*
X253659D03*
Y271197D03*
X250903D03*
Y268197D03*
X253659D03*
X245839Y275697D03*
Y269697D03*
Y272697D03*
Y266697D03*
X256886Y281877D03*
X258723Y275697D03*
Y272697D03*
Y269697D03*
Y266697D03*
X255286Y295209D03*
Y286941D03*
X256886Y284633D03*
Y297517D03*
X258386Y292453D03*
Y289697D03*
X255630Y292453D03*
Y289697D03*
X255286Y302581D03*
Y310849D03*
X256886Y300273D03*
X258386Y305337D03*
Y308093D03*
X255630Y305337D03*
Y308093D03*
X256886Y313157D03*
X248824Y320079D03*
X251580D03*
X249959Y328649D03*
Y325649D03*
Y322649D03*
X252715Y328649D03*
Y325649D03*
Y322649D03*
X244895Y321149D03*
Y327149D03*
Y324149D03*
X256886Y315913D03*
X257779Y321149D03*
Y324149D03*
Y327149D03*
X255124Y320079D03*
X243659Y341979D03*
X247681D03*
X250466Y342047D03*
X249959Y334649D03*
Y331649D03*
Y337649D03*
X252715Y334649D03*
Y331649D03*
Y337649D03*
X244895Y336149D03*
Y333149D03*
Y330149D03*
Y339149D03*
X245670Y343866D03*
X248302Y344859D03*
X253196Y342535D03*
X257779Y330149D03*
Y333149D03*
Y336149D03*
Y339149D03*
X258622Y341784D03*
X255952Y342535D03*
X245870Y346866D03*
X248510Y348629D03*
X252710Y348183D03*
X250427Y346623D03*
X252834Y345277D03*
X256358Y348190D03*
X258741Y346640D03*
X256334Y345277D03*
X268869Y250206D03*
X271252Y248656D03*
X267202Y248007D03*
X259455Y250223D03*
X264012Y249980D03*
X261372Y248217D03*
X271276Y251569D03*
X261580Y251987D03*
X274363Y257697D03*
X266543Y259197D03*
Y265197D03*
Y262197D03*
X269299Y259197D03*
X274363Y260697D03*
Y263697D03*
X269299Y265197D03*
Y262197D03*
X271658Y254311D03*
X266223Y254867D03*
X268988Y255062D03*
X266888Y252157D03*
X274414Y254311D03*
X261479Y257697D03*
Y260697D03*
Y263697D03*
X259416Y254799D03*
X262201Y254867D03*
X264212Y252980D03*
X271886Y268993D03*
X268886D03*
X265886D03*
X264386Y274057D03*
Y276813D03*
X267386Y274057D03*
X270386D03*
X273386D03*
X267386Y276813D03*
X270386D03*
X273386D03*
X262886Y281877D03*
X259886D03*
X265886D03*
X268886D03*
X271886D03*
X261479Y275697D03*
Y269697D03*
Y272697D03*
Y266697D03*
X262886Y284633D03*
X259886D03*
X261386Y289697D03*
Y292453D03*
X262886Y297517D03*
X264386Y292453D03*
Y289697D03*
X259886Y297517D03*
X265886Y284633D03*
X268886D03*
X271886D03*
X268886Y297517D03*
X265886D03*
X270386Y292453D03*
Y289697D03*
X267386D03*
Y292453D03*
X271886Y297517D03*
X273386Y292453D03*
Y289697D03*
X262886Y300273D03*
X259886D03*
X261386Y308093D03*
Y305337D03*
X264386D03*
Y308093D03*
X268886Y300273D03*
X265886D03*
X271886D03*
X267386Y308093D03*
Y305337D03*
X270386D03*
Y308093D03*
X273386Y305337D03*
Y308093D03*
X262886Y313157D03*
X259886D03*
X265886D03*
X268886D03*
X271886D03*
X262886Y315913D03*
X259886D03*
X265886D03*
X268886D03*
X271886D03*
X264386Y320977D03*
Y323733D03*
X270386Y320977D03*
X267386D03*
X273386D03*
X270386Y323733D03*
X273386D03*
X267386D03*
X271886Y328797D03*
X265599Y328649D03*
X268886Y328797D03*
X260535Y321149D03*
Y324149D03*
Y327149D03*
X273419Y339149D03*
Y336149D03*
X265599Y331649D03*
X268355D03*
Y334649D03*
X265599D03*
X268355Y337649D03*
X265599D03*
X260535Y330149D03*
Y333149D03*
Y336149D03*
Y339149D03*
X261387Y341979D03*
X265409D03*
X268194Y342047D03*
X263398Y343866D03*
X260722Y344689D03*
X273680Y342535D03*
X270924D03*
X266030Y344859D03*
X263598Y346866D03*
X260408Y348839D03*
X270438Y348183D03*
X274086Y348190D03*
X274062Y345277D03*
X270562D03*
X268155Y346623D03*
X266238Y348629D03*
X281941Y249980D03*
X277183Y250223D03*
X274900Y248663D03*
X274776Y251569D03*
X280886Y258417D03*
X283784Y258579D03*
X283716Y261364D03*
Y265386D03*
X284272Y255849D03*
X277886Y266237D03*
X280886D03*
X277119Y257697D03*
Y260697D03*
X279930Y254867D03*
X281941Y252980D03*
X279265Y252157D03*
X277144Y254799D03*
X287014Y256311D03*
X288577Y258618D03*
X286426Y260699D03*
X288603Y263175D03*
X285603Y263375D03*
X286426Y266051D03*
X283521Y268151D03*
X284272Y270821D03*
X277886Y268993D03*
X280886D03*
X274886D03*
X279386Y274057D03*
X276386D03*
X279386Y276813D03*
X276386D03*
X283716Y279092D03*
X283784Y276307D03*
X284272Y273577D03*
X274886Y281877D03*
X280886D03*
X277886D03*
X289927Y270415D03*
X288377Y268032D03*
X287014Y270439D03*
X288603Y280903D03*
X290366Y278263D03*
X289920Y274063D03*
X286596Y278471D03*
X288360Y276346D03*
X287014Y273939D03*
X285603Y281103D03*
X283716Y283114D03*
X283521Y285879D03*
X284272Y288549D03*
X280886Y284633D03*
X277886D03*
Y297517D03*
X280886D03*
X279386Y289697D03*
Y292453D03*
X274886Y284633D03*
Y297517D03*
X276386Y292453D03*
Y289697D03*
X283784Y294035D03*
X283716Y296820D03*
X284272Y291305D03*
X286426Y283779D03*
X289927Y288143D03*
X287014Y288167D03*
X288377Y285760D03*
X290366Y295991D03*
X289920Y291791D03*
X286596Y296199D03*
X288360Y294074D03*
X287014Y291667D03*
X277886Y300273D03*
X280886D03*
X279386Y308093D03*
Y305337D03*
X274886Y300273D03*
X276386Y305337D03*
Y308093D03*
X283716Y300842D03*
X283521Y303607D03*
X284272Y306277D03*
X283784Y311763D03*
X284272Y309033D03*
X280886Y313157D03*
X277886D03*
X274886D03*
X286426Y301507D03*
X285603Y298831D03*
X288603Y298631D03*
X289927Y305871D03*
X287014Y305895D03*
X288377Y303488D03*
X289920Y309519D03*
X287014Y309395D03*
X288360Y311802D03*
X280886Y315913D03*
X277886D03*
X274886D03*
X283716Y318570D03*
Y314548D03*
X283521Y321335D03*
X284272Y324005D03*
X279386Y320977D03*
X276386D03*
X279386Y323733D03*
X276386D03*
X284272Y326761D03*
X277886Y328797D03*
X280886D03*
X274886D03*
X286426Y319235D03*
X285603Y316559D03*
X288603Y316359D03*
X290366Y313719D03*
X286596Y313927D03*
X288377Y321216D03*
X289927Y323599D03*
X287014Y323623D03*
Y327123D03*
X289920Y327247D03*
X283784Y329491D03*
X283716Y332276D03*
Y336298D03*
X283521Y339063D03*
X277886Y331553D03*
X280886D03*
X274886D03*
X279386Y336617D03*
X276386D03*
X277886Y339149D03*
X283137Y341979D03*
X279115D03*
X276350Y341784D03*
X281126Y343866D03*
X278450Y344689D03*
X288360Y329530D03*
X286596Y331655D03*
X290366Y331447D03*
X288603Y334087D03*
X285603Y334287D03*
X288577Y339044D03*
X286426Y336963D03*
X287014Y341351D03*
X281126Y346866D03*
X276469Y346640D03*
X290576Y266365D03*
Y284093D03*
Y301821D03*
Y319549D03*
G54D99*
X196149Y386396D03*
X193590D03*
Y400255D03*
X196149D03*
X201267Y386396D03*
X198708D03*
Y400255D03*
X201267D03*
M02*
